(kicad_sch
	(version 20250114)
	(generator "eeschema")
	(generator_version "9.0")
	(paper "A3")
	(title_block
		(title "SDI-MIPI Video Converter")
		(date "2023-10-12")
		(rev "1.1.4")
		(comment 1 "www.antmicro.com")
		(comment 2 "Antmicro Ltd.")
	)
	(text "Soft CSI"
		(exclude_from_sim no)
		(at 59.69 68.58 0)
		(effects
			(font
				(size 3 3)
			)
			(justify left bottom)
		)
	)
	(text "FFC1 POWER SWITCH"
		(exclude_from_sim no)
		(at 137.16 195.58 0)
		(effects
			(font
				(size 5 5)
			)
			(justify left bottom)
		)
	)
	(text "USB-C CONNECTOR"
		(exclude_from_sim no)
		(at 276.86 199.39 0)
		(effects
			(font
				(size 5 5)
			)
			(justify left bottom)
		)
	)
	(text "POWER SOURCE\n"
		(exclude_from_sim no)
		(at 187.96 31.75 0)
		(effects
			(font
				(size 2 2)
			)
			(justify left bottom)
		)
	)
	(text "QWIIC CONNECTOR"
		(exclude_from_sim no)
		(at 36.83 194.31 0)
		(effects
			(font
				(size 5 5)
			)
			(justify left bottom)
		)
	)
	(text "FPGA"
		(exclude_from_sim no)
		(at 60.96 21.59 0)
		(effects
			(font
				(size 5 5)
			)
			(justify left bottom)
		)
	)
	(text "FFC1"
		(exclude_from_sim no)
		(at 194.31 29.21 0)
		(effects
			(font
				(size 3 3)
			)
			(justify left bottom)
		)
	)
	(text "USER LEDs"
		(exclude_from_sim no)
		(at 288.29 124.46 0)
		(effects
			(font
				(size 5 5)
			)
			(justify left bottom)
		)
	)
	(text "TX\n"
		(exclude_from_sim no)
		(at 383.54 223.52 0)
		(effects
			(font
				(size 1.27 1.27)
			)
			(justify left bottom)
		)
	)
	(text "CSI Connectors"
		(exclude_from_sim no)
		(at 194.31 22.86 0)
		(effects
			(font
				(size 5 5)
			)
			(justify left bottom)
		)
	)
	(text "I2S CONNECTOR\n"
		(exclude_from_sim no)
		(at 276.86 24.13 0)
		(effects
			(font
				(size 5 5)
			)
			(justify left bottom)
		)
	)
	(text "USER SWITCH"
		(exclude_from_sim no)
		(at 349.25 124.46 0)
		(effects
			(font
				(size 5 5)
			)
			(justify left bottom)
		)
	)
	(text "FFC2\n"
		(exclude_from_sim no)
		(at 255.27 29.21 0)
		(effects
			(font
				(size 3 3)
			)
			(justify left bottom)
		)
	)
	(text "Hard CSI"
		(exclude_from_sim no)
		(at 59.69 26.67 0)
		(effects
			(font
				(size 3 3)
			)
			(justify left bottom)
		)
	)
	(text "To power supply"
		(exclude_from_sim no)
		(at 233.68 162.56 0)
		(effects
			(font
				(size 1.27 1.27)
			)
			(justify left bottom)
		)
	)
	(text "RX"
		(exclude_from_sim no)
		(at 368.3 223.52 0)
		(effects
			(font
				(size 1.27 1.27)
			)
			(justify left bottom)
		)
	)
	(text "GPIO CONNECTOR"
		(exclude_from_sim no)
		(at 339.09 24.13 0)
		(effects
			(font
				(size 5 5)
			)
			(justify left bottom)
		)
	)
	(text "POWER SINK"
		(exclude_from_sim no)
		(at 251.46 31.75 0)
		(effects
			(font
				(size 2 2)
			)
			(justify left bottom)
		)
	)
	(junction
		(at 157.48 214.63)
		(diameter 0)
		(color 0 0 0 0)
	)
	(junction
		(at 312.42 201.93)
		(diameter 0)
		(color 0 0 0 0)
	)
	(junction
		(at 252.73 80.01)
		(diameter 0)
		(color 0 0 0 0)
	)
	(junction
		(at 111.76 80.01)
		(diameter 0)
		(color 0 0 0 0)
	)
	(junction
		(at 168.91 237.49)
		(diameter 0)
		(color 0 0 0 0)
	)
	(junction
		(at 191.77 80.01)
		(diameter 0)
		(color 0 0 0 0)
	)
	(junction
		(at 265.43 228.6)
		(diameter 0)
		(color 0 0 0 0)
	)
	(junction
		(at 383.54 143.51)
		(diameter 0)
		(color 0 0 0 0)
	)
	(junction
		(at 297.18 201.93)
		(diameter 0)
		(color 0 0 0 0)
	)
	(junction
		(at 147.32 153.67)
		(diameter 0)
		(color 0 0 0 0)
	)
	(junction
		(at 148.59 214.63)
		(diameter 0)
		(color 0 0 0 0)
	)
	(junction
		(at 308.61 232.41)
		(diameter 0)
		(color 0 0 0 0)
	)
	(junction
		(at 191.77 72.39)
		(diameter 0)
		(color 0 0 0 0)
	)
	(junction
		(at 96.52 276.86)
		(diameter 0)
		(color 0 0 0 0)
	)
	(junction
		(at 368.3 204.47)
		(diameter 0)
		(color 0 0 0 0)
	)
	(junction
		(at 252.73 102.87)
		(diameter 0)
		(color 0 0 0 0)
	)
	(junction
		(at 191.77 110.49)
		(diameter 0)
		(color 0 0 0 0)
	)
	(junction
		(at 252.73 163.83)
		(diameter 0)
		(color 0 0 0 0)
	)
	(junction
		(at 252.73 110.49)
		(diameter 0)
		(color 0 0 0 0)
	)
	(junction
		(at 170.18 153.67)
		(diameter 0)
		(color 0 0 0 0)
	)
	(junction
		(at 114.3 125.73)
		(diameter 0)
		(color 0 0 0 0)
	)
	(junction
		(at 264.16 226.06)
		(diameter 0)
		(color 0 0 0 0)
	)
	(junction
		(at 40.64 210.82)
		(diameter 0)
		(color 0 0 0 0)
	)
	(junction
		(at 370.84 45.72)
		(diameter 0)
		(color 0 0 0 0)
	)
	(junction
		(at 383.54 140.97)
		(diameter 0)
		(color 0 0 0 0)
	)
	(junction
		(at 191.77 102.87)
		(diameter 0)
		(color 0 0 0 0)
	)
	(junction
		(at 373.38 40.64)
		(diameter 0)
		(color 0 0 0 0)
	)
	(junction
		(at 250.19 158.75)
		(diameter 0)
		(color 0 0 0 0)
	)
	(junction
		(at 308.61 222.25)
		(diameter 0)
		(color 0 0 0 0)
	)
	(junction
		(at 372.11 43.18)
		(diameter 0)
		(color 0 0 0 0)
	)
	(junction
		(at 284.48 228.6)
		(diameter 0)
		(color 0 0 0 0)
	)
	(junction
		(at 168.91 241.3)
		(diameter 0)
		(color 0 0 0 0)
	)
	(junction
		(at 375.92 35.56)
		(diameter 0)
		(color 0 0 0 0)
	)
	(junction
		(at 191.77 166.37)
		(diameter 0)
		(color 0 0 0 0)
	)
	(junction
		(at 369.57 48.26)
		(diameter 0)
		(color 0 0 0 0)
	)
	(junction
		(at 165.1 222.25)
		(diameter 0)
		(color 0 0 0 0)
	)
	(junction
		(at 250.19 153.67)
		(diameter 0)
		(color 0 0 0 0)
	)
	(junction
		(at 158.75 158.75)
		(diameter 0)
		(color 0 0 0 0)
	)
	(junction
		(at 157.48 226.06)
		(diameter 0)
		(color 0 0 0 0)
	)
	(junction
		(at 168.91 266.7)
		(diameter 0)
		(color 0 0 0 0)
	)
	(junction
		(at 72.39 240.03)
		(diameter 0)
		(color 0 0 0 0)
	)
	(junction
		(at 374.65 38.1)
		(diameter 0)
		(color 0 0 0 0)
	)
	(junction
		(at 363.22 50.8)
		(diameter 0)
		(color 0 0 0 0)
	)
	(junction
		(at 53.34 229.87)
		(diameter 0)
		(color 0 0 0 0)
	)
	(junction
		(at 252.73 72.39)
		(diameter 0)
		(color 0 0 0 0)
	)
	(junction
		(at 179.07 158.75)
		(diameter 0)
		(color 0 0 0 0)
	)
	(junction
		(at 189.23 153.67)
		(diameter 0)
		(color 0 0 0 0)
	)
	(junction
		(at 252.73 166.37)
		(diameter 0)
		(color 0 0 0 0)
	)
	(junction
		(at 285.75 201.93)
		(diameter 0)
		(color 0 0 0 0)
	)
	(junction
		(at 148.59 252.73)
		(diameter 0)
		(color 0 0 0 0)
	)
	(junction
		(at 252.73 64.77)
		(diameter 0)
		(color 0 0 0 0)
	)
	(junction
		(at 189.23 158.75)
		(diameter 0)
		(color 0 0 0 0)
	)
	(junction
		(at 191.77 64.77)
		(diameter 0)
		(color 0 0 0 0)
	)
	(junction
		(at 278.13 220.98)
		(diameter 0)
		(color 0 0 0 0)
	)
	(junction
		(at 264.16 248.92)
		(diameter 0)
		(color 0 0 0 0)
	)
	(junction
		(at 119.38 229.87)
		(diameter 0)
		(color 0 0 0 0)
	)
	(junction
		(at 71.12 229.87)
		(diameter 0)
		(color 0 0 0 0)
	)
	(junction
		(at 191.77 163.83)
		(diameter 0)
		(color 0 0 0 0)
	)
	(junction
		(at 157.48 264.16)
		(diameter 0)
		(color 0 0 0 0)
	)
	(junction
		(at 267.97 226.06)
		(diameter 0)
		(color 0 0 0 0)
	)
	(junction
		(at 308.61 219.71)
		(diameter 0)
		(color 0 0 0 0)
	)
	(junction
		(at 360.68 45.72)
		(diameter 0)
		(color 0 0 0 0)
	)
	(junction
		(at 71.12 240.03)
		(diameter 0)
		(color 0 0 0 0)
	)
	(no_connect
		(at 194.31 128.27)
	)
	(no_connect
		(at 194.31 130.81)
	)
	(no_connect
		(at 194.31 125.73)
	)
	(no_connect
		(at 194.31 123.19)
	)
	(no_connect
		(at 194.31 113.03)
	)
	(no_connect
		(at 194.31 69.85)
	)
	(no_connect
		(at 194.31 67.31)
	)
	(no_connect
		(at 194.31 74.93)
	)
	(no_connect
		(at 194.31 77.47)
	)
	(no_connect
		(at 337.82 224.79)
	)
	(no_connect
		(at 246.38 46.99)
	)
	(no_connect
		(at 246.38 62.23)
	)
	(no_connect
		(at 262.89 238.76)
	)
	(no_connect
		(at 246.38 36.83)
	)
	(no_connect
		(at 246.38 44.45)
	)
	(no_connect
		(at 236.22 153.67)
	)
	(no_connect
		(at 246.38 41.91)
	)
	(no_connect
		(at 255.27 67.31)
	)
	(no_connect
		(at 255.27 69.85)
	)
	(no_connect
		(at 255.27 128.27)
	)
	(no_connect
		(at 255.27 125.73)
	)
	(no_connect
		(at 255.27 123.19)
	)
	(no_connect
		(at 255.27 113.03)
	)
	(no_connect
		(at 255.27 74.93)
	)
	(no_connect
		(at 255.27 77.47)
	)
	(no_connect
		(at 255.27 130.81)
	)
	(no_connect
		(at 255.27 146.05)
	)
	(no_connect
		(at 255.27 148.59)
	)
	(no_connect
		(at 255.27 151.13)
	)
	(no_connect
		(at 255.27 143.51)
	)
	(no_connect
		(at 246.38 49.53)
	)
	(no_connect
		(at 246.38 52.07)
	)
	(no_connect
		(at 262.89 241.3)
	)
	(no_connect
		(at 194.31 146.05)
	)
	(no_connect
		(at 194.31 148.59)
	)
	(no_connect
		(at 194.31 151.13)
	)
	(no_connect
		(at 194.31 143.51)
	)
	(no_connect
		(at 246.38 54.61)
	)
	(no_connect
		(at 246.38 39.37)
	)
	(no_connect
		(at 246.38 59.69)
	)
	(no_connect
		(at 337.82 222.25)
	)
	(wire
		(pts
			(xy 30.48 208.28) (xy 44.45 208.28)
		)
		(stroke
			(width 0)
			(type default)
		)
	)
	(wire
		(pts
			(xy 165.1 222.25) (xy 165.1 229.87)
		)
		(stroke
			(width 0)
			(type default)
		)
	)
	(wire
		(pts
			(xy 375.92 35.56) (xy 377.19 35.56)
		)
		(stroke
			(width 0)
			(type default)
		)
	)
	(wire
		(pts
			(xy 72.39 240.03) (xy 72.39 242.57)
		)
		(stroke
			(width 0)
			(type default)
		)
	)
	(wire
		(pts
			(xy 63.5 33.02) (xy 50.8 33.02)
		)
		(stroke
			(width 0)
			(type default)
		)
	)
	(wire
		(pts
			(xy 96.52 276.86) (xy 93.98 276.86)
		)
		(stroke
			(width 0)
			(type default)
		)
	)
	(wire
		(pts
			(xy 308.61 232.41) (xy 308.61 236.22)
		)
		(stroke
			(width 0)
			(type default)
		)
	)
	(wire
		(pts
			(xy 30.48 205.74) (xy 44.45 205.74)
		)
		(stroke
			(width 0)
			(type default)
		)
	)
	(wire
		(pts
			(xy 189.23 153.67) (xy 194.31 153.67)
		)
		(stroke
			(width 0)
			(type default)
		)
	)
	(wire
		(pts
			(xy 172.72 222.25) (xy 165.1 222.25)
		)
		(stroke
			(width 0)
			(type default)
		)
	)
	(wire
		(pts
			(xy 172.72 264.16) (xy 157.48 264.16)
		)
		(stroke
			(width 0)
			(type default)
		)
	)
	(wire
		(pts
			(xy 158.75 166.37) (xy 158.75 168.91)
		)
		(stroke
			(width 0)
			(type default)
		)
	)
	(wire
		(pts
			(xy 299.72 62.23) (xy 300.99 62.23)
		)
		(stroke
			(width 0)
			(type default)
		)
	)
	(wire
		(pts
			(xy 168.91 228.6) (xy 172.72 228.6)
		)
		(stroke
			(width 0)
			(type default)
		)
	)
	(wire
		(pts
			(xy 285.75 201.93) (xy 297.18 201.93)
		)
		(stroke
			(width 0)
			(type default)
		)
	)
	(wire
		(pts
			(xy 186.69 133.35) (xy 186.69 135.89)
		)
		(stroke
			(width 0)
			(type default)
		)
	)
	(wire
		(pts
			(xy 119.38 229.87) (xy 129.54 229.87)
		)
		(stroke
			(width 0)
			(type default)
		)
	)
	(wire
		(pts
			(xy 284.48 237.49) (xy 284.48 236.22)
		)
		(stroke
			(width 0)
			(type default)
		)
	)
	(wire
		(pts
			(xy 157.48 118.11) (xy 176.53 118.11)
		)
		(stroke
			(width 0)
			(type default)
		)
	)
	(wire
		(pts
			(xy 231.14 135.89) (xy 255.27 135.89)
		)
		(stroke
			(width 0)
			(type default)
		)
	)
	(wire
		(pts
			(xy 262.89 228.6) (xy 265.43 228.6)
		)
		(stroke
			(width 0)
			(type default)
		)
	)
	(wire
		(pts
			(xy 92.71 130.81) (xy 78.74 130.81)
		)
		(stroke
			(width 0)
			(type default)
		)
	)
	(wire
		(pts
			(xy 199.39 264.16) (xy 199.39 266.7)
		)
		(stroke
			(width 0)
			(type default)
		)
	)
	(wire
		(pts
			(xy 285.75 209.55) (xy 285.75 210.82)
		)
		(stroke
			(width 0)
			(type default)
		)
	)
	(wire
		(pts
			(xy 147.32 173.99) (xy 147.32 176.53)
		)
		(stroke
			(width 0)
			(type default)
		)
	)
	(wire
		(pts
			(xy 318.77 154.94) (xy 318.77 157.48)
		)
		(stroke
			(width 0)
			(type default)
		)
	)
	(wire
		(pts
			(xy 87.63 205.74) (xy 87.63 208.28)
		)
		(stroke
			(width 0)
			(type default)
		)
	)
	(wire
		(pts
			(xy 111.76 78.74) (xy 111.76 80.01)
		)
		(stroke
			(width 0)
			(type default)
		)
	)
	(wire
		(pts
			(xy 264.16 226.06) (xy 267.97 226.06)
		)
		(stroke
			(width 0)
			(type default)
		)
	)
	(wire
		(pts
			(xy 381 80.01) (xy 370.84 80.01)
		)
		(stroke
			(width 0)
			(type default)
		)
	)
	(wire
		(pts
			(xy 114.3 135.89) (xy 114.3 137.16)
		)
		(stroke
			(width 0)
			(type default)
		)
	)
	(wire
		(pts
			(xy 245.11 115.57) (xy 255.27 115.57)
		)
		(stroke
			(width 0)
			(type default)
		)
	)
	(wire
		(pts
			(xy 313.69 237.49) (xy 314.96 237.49)
		)
		(stroke
			(width 0)
			(type default)
		)
	)
	(polyline
		(pts
			(xy 132.08 12.7) (xy 132.08 284.48)
		)
		(stroke
			(width 0)
			(type default)
		)
	)
	(wire
		(pts
			(xy 181.61 133.35) (xy 186.69 133.35)
		)
		(stroke
			(width 0)
			(type default)
		)
	)
	(wire
		(pts
			(xy 292.1 228.6) (xy 314.96 228.6)
		)
		(stroke
			(width 0)
			(type default)
		)
	)
	(wire
		(pts
			(xy 63.5 41.91) (xy 50.8 41.91)
		)
		(stroke
			(width 0)
			(type default)
		)
	)
	(wire
		(pts
			(xy 190.5 226.06) (xy 199.39 226.06)
		)
		(stroke
			(width 0)
			(type default)
		)
	)
	(wire
		(pts
			(xy 78.74 156.21) (xy 96.52 156.21)
		)
		(stroke
			(width 0)
			(type default)
		)
	)
	(wire
		(pts
			(xy 252.73 166.37) (xy 255.27 166.37)
		)
		(stroke
			(width 0)
			(type default)
		)
	)
	(wire
		(pts
			(xy 157.48 214.63) (xy 157.48 217.17)
		)
		(stroke
			(width 0)
			(type default)
		)
	)
	(wire
		(pts
			(xy 157.48 113.03) (xy 176.53 113.03)
		)
		(stroke
			(width 0)
			(type default)
		)
	)
	(wire
		(pts
			(xy 105.41 92.71) (xy 92.71 92.71)
		)
		(stroke
			(width 0)
			(type default)
		)
	)
	(wire
		(pts
			(xy 264.16 246.38) (xy 262.89 246.38)
		)
		(stroke
			(width 0)
			(type default)
		)
	)
	(wire
		(pts
			(xy 252.73 110.49) (xy 252.73 163.83)
		)
		(stroke
			(width 0)
			(type default)
		)
	)
	(wire
		(pts
			(xy 72.39 247.65) (xy 72.39 248.92)
		)
		(stroke
			(width 0)
			(type default)
		)
	)
	(wire
		(pts
			(xy 186.69 140.97) (xy 186.69 138.43)
		)
		(stroke
			(width 0)
			(type default)
		)
	)
	(wire
		(pts
			(xy 312.42 217.17) (xy 312.42 201.93)
		)
		(stroke
			(width 0)
			(type default)
		)
	)
	(wire
		(pts
			(xy 148.59 265.43) (xy 148.59 271.78)
		)
		(stroke
			(width 0)
			(type default)
		)
	)
	(wire
		(pts
			(xy 381 72.39) (xy 374.65 72.39)
		)
		(stroke
			(width 0)
			(type default)
		)
	)
	(wire
		(pts
			(xy 193.04 266.7) (xy 190.5 266.7)
		)
		(stroke
			(width 0)
			(type default)
		)
	)
	(wire
		(pts
			(xy 63.5 48.26) (xy 50.8 48.26)
		)
		(stroke
			(width 0)
			(type default)
		)
	)
	(wire
		(pts
			(xy 170.18 153.67) (xy 189.23 153.67)
		)
		(stroke
			(width 0)
			(type default)
		)
	)
	(wire
		(pts
			(xy 250.19 153.67) (xy 255.27 153.67)
		)
		(stroke
			(width 0)
			(type default)
		)
	)
	(wire
		(pts
			(xy 177.8 36.83) (xy 194.31 36.83)
		)
		(stroke
			(width 0)
			(type default)
		)
	)
	(wire
		(pts
			(xy 177.8 49.53) (xy 194.31 49.53)
		)
		(stroke
			(width 0)
			(type default)
		)
	)
	(wire
		(pts
			(xy 177.8 107.95) (xy 194.31 107.95)
		)
		(stroke
			(width 0)
			(type default)
		)
	)
	(polyline
		(pts
			(xy 407.67 88.9) (xy 407.67 87.63)
		)
		(stroke
			(width 0)
			(type default)
		)
	)
	(wire
		(pts
			(xy 189.23 140.97) (xy 194.31 140.97)
		)
		(stroke
			(width 0)
			(type default)
		)
	)
	(wire
		(pts
			(xy 241.3 118.11) (xy 255.27 118.11)
		)
		(stroke
			(width 0)
			(type default)
		)
	)
	(wire
		(pts
			(xy 114.3 125.73) (xy 114.3 130.81)
		)
		(stroke
			(width 0)
			(type default)
		)
	)
	(wire
		(pts
			(xy 306.07 154.94) (xy 306.07 157.48)
		)
		(stroke
			(width 0)
			(type default)
		)
	)
	(wire
		(pts
			(xy 313.69 242.57) (xy 313.69 237.49)
		)
		(stroke
			(width 0)
			(type default)
		)
	)
	(wire
		(pts
			(xy 236.22 153.67) (xy 250.19 153.67)
		)
		(stroke
			(width 0)
			(type default)
		)
	)
	(wire
		(pts
			(xy 92.71 176.53) (xy 78.74 176.53)
		)
		(stroke
			(width 0)
			(type default)
		)
	)
	(wire
		(pts
			(xy 78.74 196.85) (xy 87.63 196.85)
		)
		(stroke
			(width 0)
			(type default)
		)
	)
	(wire
		(pts
			(xy 189.23 158.75) (xy 189.23 161.29)
		)
		(stroke
			(width 0)
			(type default)
		)
	)
	(wire
		(pts
			(xy 363.22 50.8) (xy 377.19 50.8)
		)
		(stroke
			(width 0)
			(type default)
		)
	)
	(wire
		(pts
			(xy 255.27 57.15) (xy 252.73 57.15)
		)
		(stroke
			(width 0)
			(type default)
		)
	)
	(wire
		(pts
			(xy 191.77 80.01) (xy 194.31 80.01)
		)
		(stroke
			(width 0)
			(type default)
		)
	)
	(wire
		(pts
			(xy 278.13 218.44) (xy 271.78 218.44)
		)
		(stroke
			(width 0)
			(type default)
		)
	)
	(wire
		(pts
			(xy 92.71 80.01) (xy 111.76 80.01)
		)
		(stroke
			(width 0)
			(type default)
		)
	)
	(wire
		(pts
			(xy 147.32 153.67) (xy 147.32 161.29)
		)
		(stroke
			(width 0)
			(type default)
		)
	)
	(wire
		(pts
			(xy 237.49 82.55) (xy 255.27 82.55)
		)
		(stroke
			(width 0)
			(type default)
		)
	)
	(wire
		(pts
			(xy 295.91 133.35) (xy 306.07 133.35)
		)
		(stroke
			(width 0)
			(type default)
		)
	)
	(wire
		(pts
			(xy 80.01 236.22) (xy 80.01 240.03)
		)
		(stroke
			(width 0)
			(type default)
		)
	)
	(wire
		(pts
			(xy 237.49 107.95) (xy 255.27 107.95)
		)
		(stroke
			(width 0)
			(type default)
		)
	)
	(wire
		(pts
			(xy 191.77 110.49) (xy 194.31 110.49)
		)
		(stroke
			(width 0)
			(type default)
		)
	)
	(polyline
		(pts
			(xy 274.32 93.98) (xy 407.67 93.98)
		)
		(stroke
			(width 0)
			(type default)
		)
	)
	(wire
		(pts
			(xy 375.92 69.85) (xy 375.92 35.56)
		)
		(stroke
			(width 0)
			(type default)
		)
	)
	(wire
		(pts
			(xy 337.82 237.49) (xy 340.36 237.49)
		)
		(stroke
			(width 0)
			(type default)
		)
	)
	(wire
		(pts
			(xy 194.31 57.15) (xy 191.77 57.15)
		)
		(stroke
			(width 0)
			(type default)
		)
	)
	(wire
		(pts
			(xy 337.82 219.71) (xy 342.9 219.71)
		)
		(stroke
			(width 0)
			(type default)
		)
	)
	(wire
		(pts
			(xy 189.23 158.75) (xy 194.31 158.75)
		)
		(stroke
			(width 0)
			(type default)
		)
	)
	(wire
		(pts
			(xy 105.41 105.41) (xy 92.71 105.41)
		)
		(stroke
			(width 0)
			(type default)
		)
	)
	(wire
		(pts
			(xy 342.9 33.02) (xy 342.9 35.56)
		)
		(stroke
			(width 0)
			(type default)
		)
	)
	(wire
		(pts
			(xy 381 74.93) (xy 373.38 74.93)
		)
		(stroke
			(width 0)
			(type default)
		)
	)
	(wire
		(pts
			(xy 215.9 113.03) (xy 236.22 113.03)
		)
		(stroke
			(width 0)
			(type default)
		)
	)
	(wire
		(pts
			(xy 22.86 205.74) (xy 25.4 205.74)
		)
		(stroke
			(width 0)
			(type default)
		)
	)
	(wire
		(pts
			(xy 199.39 233.68) (xy 199.39 234.95)
		)
		(stroke
			(width 0)
			(type default)
		)
	)
	(wire
		(pts
			(xy 250.19 161.29) (xy 255.27 161.29)
		)
		(stroke
			(width 0)
			(type default)
		)
	)
	(polyline
		(pts
			(xy 12.7 185.42) (xy 274.32 185.42)
		)
		(stroke
			(width 0)
			(type default)
		)
	)
	(wire
		(pts
			(xy 172.72 226.06) (xy 157.48 226.06)
		)
		(stroke
			(width 0)
			(type default)
		)
	)
	(wire
		(pts
			(xy 95.25 146.05) (xy 78.74 146.05)
		)
		(stroke
			(width 0)
			(type default)
		)
	)
	(wire
		(pts
			(xy 194.31 156.21) (xy 189.23 156.21)
		)
		(stroke
			(width 0)
			(type default)
		)
	)
	(wire
		(pts
			(xy 255.27 110.49) (xy 252.73 110.49)
		)
		(stroke
			(width 0)
			(type default)
		)
	)
	(polyline
		(pts
			(xy 339.09 12.7) (xy 339.09 185.42)
		)
		(stroke
			(width 0)
			(type default)
		)
	)
	(wire
		(pts
			(xy 237.49 95.25) (xy 255.27 95.25)
		)
		(stroke
			(width 0)
			(type default)
		)
	)
	(wire
		(pts
			(xy 262.89 248.92) (xy 264.16 248.92)
		)
		(stroke
			(width 0)
			(type default)
		)
	)
	(wire
		(pts
			(xy 191.77 163.83) (xy 191.77 166.37)
		)
		(stroke
			(width 0)
			(type default)
		)
	)
	(wire
		(pts
			(xy 308.61 204.47) (xy 368.3 204.47)
		)
		(stroke
			(width 0)
			(type default)
		)
	)
	(wire
		(pts
			(xy 191.77 64.77) (xy 191.77 72.39)
		)
		(stroke
			(width 0)
			(type default)
		)
	)
	(wire
		(pts
			(xy 360.68 45.72) (xy 360.68 52.07)
		)
		(stroke
			(width 0)
			(type default)
		)
	)
	(wire
		(pts
			(xy 118.11 48.26) (xy 105.41 48.26)
		)
		(stroke
			(width 0)
			(type default)
		)
	)
	(wire
		(pts
			(xy 177.8 87.63) (xy 194.31 87.63)
		)
		(stroke
			(width 0)
			(type default)
		)
	)
	(wire
		(pts
			(xy 92.71 133.35) (xy 78.74 133.35)
		)
		(stroke
			(width 0)
			(type default)
		)
	)
	(wire
		(pts
			(xy 252.73 166.37) (xy 252.73 168.91)
		)
		(stroke
			(width 0)
			(type default)
		)
	)
	(wire
		(pts
			(xy 299.72 54.61) (xy 300.99 54.61)
		)
		(stroke
			(width 0)
			(type default)
		)
	)
	(wire
		(pts
			(xy 207.01 143.51) (xy 224.79 143.51)
		)
		(stroke
			(width 0)
			(type default)
		)
	)
	(wire
		(pts
			(xy 63.5 54.61) (xy 50.8 54.61)
		)
		(stroke
			(width 0)
			(type default)
		)
	)
	(wire
		(pts
			(xy 246.38 41.91) (xy 255.27 41.91)
		)
		(stroke
			(width 0)
			(type default)
		)
	)
	(wire
		(pts
			(xy 158.75 241.3) (xy 168.91 241.3)
		)
		(stroke
			(width 0)
			(type default)
		)
	)
	(wire
		(pts
			(xy 218.44 135.89) (xy 226.06 135.89)
		)
		(stroke
			(width 0)
			(type default)
		)
	)
	(wire
		(pts
			(xy 105.41 82.55) (xy 92.71 82.55)
		)
		(stroke
			(width 0)
			(type default)
		)
	)
	(wire
		(pts
			(xy 200.66 222.25) (xy 190.5 222.25)
		)
		(stroke
			(width 0)
			(type default)
		)
	)
	(wire
		(pts
			(xy 255.27 156.21) (xy 250.19 156.21)
		)
		(stroke
			(width 0)
			(type default)
		)
	)
	(wire
		(pts
			(xy 297.18 201.93) (xy 312.42 201.93)
		)
		(stroke
			(width 0)
			(type default)
		)
	)
	(wire
		(pts
			(xy 308.61 222.25) (xy 314.96 222.25)
		)
		(stroke
			(width 0)
			(type default)
		)
	)
	(wire
		(pts
			(xy 311.15 57.15) (xy 312.42 57.15)
		)
		(stroke
			(width 0)
			(type default)
		)
	)
	(wire
		(pts
			(xy 353.06 35.56) (xy 375.92 35.56)
		)
		(stroke
			(width 0)
			(type default)
		)
	)
	(wire
		(pts
			(xy 87.63 196.85) (xy 87.63 200.66)
		)
		(stroke
			(width 0)
			(type default)
		)
	)
	(wire
		(pts
			(xy 262.89 226.06) (xy 264.16 226.06)
		)
		(stroke
			(width 0)
			(type default)
		)
	)
	(wire
		(pts
			(xy 34.29 198.12) (xy 34.29 203.2)
		)
		(stroke
			(width 0)
			(type default)
		)
	)
	(wire
		(pts
			(xy 360.68 45.72) (xy 370.84 45.72)
		)
		(stroke
			(width 0)
			(type default)
		)
	)
	(wire
		(pts
			(xy 252.73 64.77) (xy 252.73 72.39)
		)
		(stroke
			(width 0)
			(type default)
		)
	)
	(wire
		(pts
			(xy 383.54 229.87) (xy 383.54 234.95)
		)
		(stroke
			(width 0)
			(type default)
		)
	)
	(wire
		(pts
			(xy 34.29 203.2) (xy 44.45 203.2)
		)
		(stroke
			(width 0)
			(type default)
		)
	)
	(wire
		(pts
			(xy 181.61 113.03) (xy 185.42 113.03)
		)
		(stroke
			(width 0)
			(type default)
		)
	)
	(wire
		(pts
			(xy 165.1 260.35) (xy 165.1 252.73)
		)
		(stroke
			(width 0)
			(type default)
		)
	)
	(wire
		(pts
			(xy 241.3 113.03) (xy 245.11 113.03)
		)
		(stroke
			(width 0)
			(type default)
		)
	)
	(wire
		(pts
			(xy 181.61 130.81) (xy 189.23 130.81)
		)
		(stroke
			(width 0)
			(type default)
		)
	)
	(wire
		(pts
			(xy 177.8 62.23) (xy 194.31 62.23)
		)
		(stroke
			(width 0)
			(type default)
		)
	)
	(wire
		(pts
			(xy 105.41 95.25) (xy 92.71 95.25)
		)
		(stroke
			(width 0)
			(type default)
		)
	)
	(wire
		(pts
			(xy 172.72 260.35) (xy 165.1 260.35)
		)
		(stroke
			(width 0)
			(type default)
		)
	)
	(wire
		(pts
			(xy 252.73 57.15) (xy 252.73 64.77)
		)
		(stroke
			(width 0)
			(type default)
		)
	)
	(wire
		(pts
			(xy 181.61 140.97) (xy 186.69 140.97)
		)
		(stroke
			(width 0)
			(type default)
		)
	)
	(wire
		(pts
			(xy 308.61 222.25) (xy 308.61 232.41)
		)
		(stroke
			(width 0)
			(type default)
		)
	)
	(wire
		(pts
			(xy 185.42 123.19) (xy 185.42 120.65)
		)
		(stroke
			(width 0)
			(type default)
		)
	)
	(wire
		(pts
			(xy 363.22 48.26) (xy 369.57 48.26)
		)
		(stroke
			(width 0)
			(type default)
		)
	)
	(polyline
		(pts
			(xy 274.32 12.7) (xy 274.32 185.42)
		)
		(stroke
			(width 0)
			(type default)
		)
	)
	(wire
		(pts
			(xy 368.3 229.87) (xy 368.3 232.41)
		)
		(stroke
			(width 0)
			(type default)
		)
	)
	(wire
		(pts
			(xy 118.11 35.56) (xy 105.41 35.56)
		)
		(stroke
			(width 0)
			(type default)
		)
	)
	(wire
		(pts
			(xy 383.54 146.05) (xy 383.54 143.51)
		)
		(stroke
			(width 0)
			(type default)
		)
	)
	(wire
		(pts
			(xy 381 69.85) (xy 375.92 69.85)
		)
		(stroke
			(width 0)
			(type default)
		)
	)
	(wire
		(pts
			(xy 168.91 237.49) (xy 168.91 241.3)
		)
		(stroke
			(width 0)
			(type default)
		)
	)
	(wire
		(pts
			(xy 365.76 140.97) (xy 369.57 140.97)
		)
		(stroke
			(width 0)
			(type default)
		)
	)
	(wire
		(pts
			(xy 285.75 201.93) (xy 285.75 204.47)
		)
		(stroke
			(width 0)
			(type default)
		)
	)
	(wire
		(pts
			(xy 299.72 63.5) (xy 299.72 62.23)
		)
		(stroke
			(width 0)
			(type default)
		)
	)
	(wire
		(pts
			(xy 246.38 39.37) (xy 255.27 39.37)
		)
		(stroke
			(width 0)
			(type default)
		)
	)
	(wire
		(pts
			(xy 63.5 45.72) (xy 50.8 45.72)
		)
		(stroke
			(width 0)
			(type default)
		)
	)
	(wire
		(pts
			(xy 250.19 156.21) (xy 250.19 153.67)
		)
		(stroke
			(width 0)
			(type default)
		)
	)
	(wire
		(pts
			(xy 368.3 219.71) (xy 368.3 224.79)
		)
		(stroke
			(width 0)
			(type default)
		)
	)
	(wire
		(pts
			(xy 191.77 72.39) (xy 194.31 72.39)
		)
		(stroke
			(width 0)
			(type default)
		)
	)
	(wire
		(pts
			(xy 96.52 276.86) (xy 106.68 276.86)
		)
		(stroke
			(width 0)
			(type default)
		)
	)
	(wire
		(pts
			(xy 181.61 123.19) (xy 185.42 123.19)
		)
		(stroke
			(width 0)
			(type default)
		)
	)
	(wire
		(pts
			(xy 297.18 204.47) (xy 297.18 201.93)
		)
		(stroke
			(width 0)
			(type default)
		)
	)
	(wire
		(pts
			(xy 255.27 72.39) (xy 252.73 72.39)
		)
		(stroke
			(width 0)
			(type default)
		)
	)
	(wire
		(pts
			(xy 118.11 33.02) (xy 105.41 33.02)
		)
		(stroke
			(width 0)
			(type default)
		)
	)
	(wire
		(pts
			(xy 71.12 229.87) (xy 85.09 229.87)
		)
		(stroke
			(width 0)
			(type default)
		)
	)
	(wire
		(pts
			(xy 383.54 143.51) (xy 383.54 140.97)
		)
		(stroke
			(width 0)
			(type default)
		)
	)
	(wire
		(pts
			(xy 245.11 113.03) (xy 245.11 115.57)
		)
		(stroke
			(width 0)
			(type default)
		)
	)
	(wire
		(pts
			(xy 373.38 40.64) (xy 377.19 40.64)
		)
		(stroke
			(width 0)
			(type default)
		)
	)
	(wire
		(pts
			(xy 359.41 43.18) (xy 372.11 43.18)
		)
		(stroke
			(width 0)
			(type default)
		)
	)
	(wire
		(pts
			(xy 237.49 92.71) (xy 255.27 92.71)
		)
		(stroke
			(width 0)
			(type default)
		)
	)
	(wire
		(pts
			(xy 369.57 138.43) (xy 368.3 138.43)
		)
		(stroke
			(width 0)
			(type default)
		)
	)
	(wire
		(pts
			(xy 363.22 50.8) (xy 363.22 54.61)
		)
		(stroke
			(width 0)
			(type default)
		)
	)
	(wire
		(pts
			(xy 105.41 85.09) (xy 92.71 85.09)
		)
		(stroke
			(width 0)
			(type default)
		)
	)
	(wire
		(pts
			(xy 318.77 128.27) (xy 318.77 138.43)
		)
		(stroke
			(width 0)
			(type default)
		)
	)
	(wire
		(pts
			(xy 267.97 226.06) (xy 267.97 231.14)
		)
		(stroke
			(width 0)
			(type default)
		)
	)
	(wire
		(pts
			(xy 95.25 128.27) (xy 78.74 128.27)
		)
		(stroke
			(width 0)
			(type default)
		)
	)
	(wire
		(pts
			(xy 191.77 166.37) (xy 191.77 168.91)
		)
		(stroke
			(width 0)
			(type default)
		)
	)
	(wire
		(pts
			(xy 118.11 60.96) (xy 105.41 60.96)
		)
		(stroke
			(width 0)
			(type default)
		)
	)
	(wire
		(pts
			(xy 252.73 163.83) (xy 255.27 163.83)
		)
		(stroke
			(width 0)
			(type default)
		)
	)
	(wire
		(pts
			(xy 369.57 48.26) (xy 377.19 48.26)
		)
		(stroke
			(width 0)
			(type default)
		)
	)
	(wire
		(pts
			(xy 191.77 166.37) (xy 194.31 166.37)
		)
		(stroke
			(width 0)
			(type default)
		)
	)
	(wire
		(pts
			(xy 170.18 153.67) (xy 170.18 166.37)
		)
		(stroke
			(width 0)
			(type default)
		)
	)
	(wire
		(pts
			(xy 374.65 72.39) (xy 374.65 38.1)
		)
		(stroke
			(width 0)
			(type default)
		)
	)
	(wire
		(pts
			(xy 191.77 57.15) (xy 191.77 64.77)
		)
		(stroke
			(width 0)
			(type default)
		)
	)
	(wire
		(pts
			(xy 95.25 158.75) (xy 78.74 158.75)
		)
		(stroke
			(width 0)
			(type default)
		)
	)
	(wire
		(pts
			(xy 78.74 153.67) (xy 96.52 153.67)
		)
		(stroke
			(width 0)
			(type default)
		)
	)
	(wire
		(pts
			(xy 308.61 241.3) (xy 308.61 242.57)
		)
		(stroke
			(width 0)
			(type default)
		)
	)
	(wire
		(pts
			(xy 165.1 222.25) (xy 165.1 214.63)
		)
		(stroke
			(width 0)
			(type default)
		)
	)
	(wire
		(pts
			(xy 110.49 233.68) (xy 110.49 237.49)
		)
		(stroke
			(width 0)
			(type default)
		)
	)
	(wire
		(pts
			(xy 246.38 49.53) (xy 255.27 49.53)
		)
		(stroke
			(width 0)
			(type default)
		)
	)
	(wire
		(pts
			(xy 181.61 118.11) (xy 194.31 118.11)
		)
		(stroke
			(width 0)
			(type default)
		)
	)
	(wire
		(pts
			(xy 118.11 39.37) (xy 105.41 39.37)
		)
		(stroke
			(width 0)
			(type default)
		)
	)
	(wire
		(pts
			(xy 194.31 133.35) (xy 189.23 133.35)
		)
		(stroke
			(width 0)
			(type default)
		)
	)
	(wire
		(pts
			(xy 190.5 228.6) (xy 193.04 228.6)
		)
		(stroke
			(width 0)
			(type default)
		)
	)
	(wire
		(pts
			(xy 177.8 90.17) (xy 194.31 90.17)
		)
		(stroke
			(width 0)
			(type default)
		)
	)
	(wire
		(pts
			(xy 215.9 123.19) (xy 236.22 123.19)
		)
		(stroke
			(width 0)
			(type default)
		)
	)
	(wire
		(pts
			(xy 372.11 77.47) (xy 372.11 43.18)
		)
		(stroke
			(width 0)
			(type default)
		)
	)
	(wire
		(pts
			(xy 271.78 220.98) (xy 278.13 220.98)
		)
		(stroke
			(width 0)
			(type default)
		)
	)
	(wire
		(pts
			(xy 177.8 59.69) (xy 194.31 59.69)
		)
		(stroke
			(width 0)
			(type default)
		)
	)
	(wire
		(pts
			(xy 314.96 219.71) (xy 308.61 219.71)
		)
		(stroke
			(width 0)
			(type default)
		)
	)
	(wire
		(pts
			(xy 95.25 161.29) (xy 78.74 161.29)
		)
		(stroke
			(width 0)
			(type default)
		)
	)
	(wire
		(pts
			(xy 370.84 45.72) (xy 377.19 45.72)
		)
		(stroke
			(width 0)
			(type default)
		)
	)
	(wire
		(pts
			(xy 177.8 52.07) (xy 194.31 52.07)
		)
		(stroke
			(width 0)
			(type default)
		)
	)
	(wire
		(pts
			(xy 53.34 229.87) (xy 53.34 233.68)
		)
		(stroke
			(width 0)
			(type default)
		)
	)
	(wire
		(pts
			(xy 92.71 173.99) (xy 78.74 173.99)
		)
		(stroke
			(width 0)
			(type default)
		)
	)
	(wire
		(pts
			(xy 308.61 232.41) (xy 314.96 232.41)
		)
		(stroke
			(width 0)
			(type default)
		)
	)
	(wire
		(pts
			(xy 381 77.47) (xy 372.11 77.47)
		)
		(stroke
			(width 0)
			(type default)
		)
	)
	(wire
		(pts
			(xy 189.23 143.51) (xy 189.23 140.97)
		)
		(stroke
			(width 0)
			(type default)
		)
	)
	(wire
		(pts
			(xy 267.97 237.49) (xy 267.97 236.22)
		)
		(stroke
			(width 0)
			(type default)
		)
	)
	(wire
		(pts
			(xy 246.38 52.07) (xy 255.27 52.07)
		)
		(stroke
			(width 0)
			(type default)
		)
	)
	(wire
		(pts
			(xy 92.71 148.59) (xy 78.74 148.59)
		)
		(stroke
			(width 0)
			(type default)
		)
	)
	(wire
		(pts
			(xy 157.48 264.16) (xy 157.48 265.43)
		)
		(stroke
			(width 0)
			(type default)
		)
	)
	(wire
		(pts
			(xy 191.77 102.87) (xy 191.77 110.49)
		)
		(stroke
			(width 0)
			(type default)
		)
	)
	(wire
		(pts
			(xy 373.38 74.93) (xy 373.38 40.64)
		)
		(stroke
			(width 0)
			(type default)
		)
	)
	(wire
		(pts
			(xy 262.89 213.36) (xy 274.32 213.36)
		)
		(stroke
			(width 0)
			(type default)
		)
	)
	(wire
		(pts
			(xy 250.19 158.75) (xy 250.19 161.29)
		)
		(stroke
			(width 0)
			(type default)
		)
	)
	(wire
		(pts
			(xy 278.13 237.49) (xy 278.13 220.98)
		)
		(stroke
			(width 0)
			(type default)
		)
	)
	(wire
		(pts
			(xy 245.11 120.65) (xy 245.11 123.19)
		)
		(stroke
			(width 0)
			(type default)
		)
	)
	(wire
		(pts
			(xy 255.27 120.65) (xy 245.11 120.65)
		)
		(stroke
			(width 0)
			(type default)
		)
	)
	(wire
		(pts
			(xy 177.8 41.91) (xy 194.31 41.91)
		)
		(stroke
			(width 0)
			(type default)
		)
	)
	(wire
		(pts
			(xy 262.89 233.68) (xy 265.43 233.68)
		)
		(stroke
			(width 0)
			(type default)
		)
	)
	(wire
		(pts
			(xy 312.42 52.07) (xy 311.15 52.07)
		)
		(stroke
			(width 0)
			(type default)
		)
	)
	(wire
		(pts
			(xy 246.38 59.69) (xy 255.27 59.69)
		)
		(stroke
			(width 0)
			(type default)
		)
	)
	(wire
		(pts
			(xy 95.25 140.97) (xy 78.74 140.97)
		)
		(stroke
			(width 0)
			(type default)
		)
	)
	(wire
		(pts
			(xy 80.01 236.22) (xy 85.09 236.22)
		)
		(stroke
			(width 0)
			(type default)
		)
	)
	(wire
		(pts
			(xy 165.1 237.49) (xy 168.91 237.49)
		)
		(stroke
			(width 0)
			(type default)
		)
	)
	(wire
		(pts
			(xy 71.12 229.87) (xy 71.12 232.41)
		)
		(stroke
			(width 0)
			(type default)
		)
	)
	(wire
		(pts
			(xy 252.73 72.39) (xy 252.73 80.01)
		)
		(stroke
			(width 0)
			(type default)
		)
	)
	(wire
		(pts
			(xy 236.22 138.43) (xy 255.27 138.43)
		)
		(stroke
			(width 0)
			(type default)
		)
	)
	(wire
		(pts
			(xy 148.59 227.33) (xy 148.59 233.68)
		)
		(stroke
			(width 0)
			(type default)
		)
	)
	(wire
		(pts
			(xy 372.11 43.18) (xy 377.19 43.18)
		)
		(stroke
			(width 0)
			(type default)
		)
	)
	(wire
		(pts
			(xy 274.32 201.93) (xy 285.75 201.93)
		)
		(stroke
			(width 0)
			(type default)
		)
	)
	(wire
		(pts
			(xy 110.49 242.57) (xy 110.49 243.84)
		)
		(stroke
			(width 0)
			(type default)
		)
	)
	(wire
		(pts
			(xy 148.59 214.63) (xy 148.59 209.55)
		)
		(stroke
			(width 0)
			(type default)
		)
	)
	(wire
		(pts
			(xy 105.41 236.22) (xy 105.41 243.84)
		)
		(stroke
			(width 0)
			(type default)
		)
	)
	(wire
		(pts
			(xy 262.89 231.14) (xy 264.16 231.14)
		)
		(stroke
			(width 0)
			(type default)
		)
	)
	(wire
		(pts
			(xy 168.91 237.49) (xy 168.91 228.6)
		)
		(stroke
			(width 0)
			(type default)
		)
	)
	(wire
		(pts
			(xy 306.07 143.51) (xy 306.07 149.86)
		)
		(stroke
			(width 0)
			(type default)
		)
	)
	(wire
		(pts
			(xy 168.91 241.3) (xy 168.91 266.7)
		)
		(stroke
			(width 0)
			(type default)
		)
	)
	(wire
		(pts
			(xy 383.54 140.97) (xy 382.27 140.97)
		)
		(stroke
			(width 0)
			(type default)
		)
	)
	(wire
		(pts
			(xy 71.12 240.03) (xy 72.39 240.03)
		)
		(stroke
			(width 0)
			(type default)
		)
	)
	(wire
		(pts
			(xy 22.86 198.12) (xy 34.29 198.12)
		)
		(stroke
			(width 0)
			(type default)
		)
	)
	(wire
		(pts
			(xy 177.8 44.45) (xy 194.31 44.45)
		)
		(stroke
			(width 0)
			(type default)
		)
	)
	(wire
		(pts
			(xy 92.71 135.89) (xy 78.74 135.89)
		)
		(stroke
			(width 0)
			(type default)
		)
	)
	(wire
		(pts
			(xy 229.87 143.51) (xy 236.22 143.51)
		)
		(stroke
			(width 0)
			(type default)
		)
	)
	(wire
		(pts
			(xy 63.5 52.07) (xy 50.8 52.07)
		)
		(stroke
			(width 0)
			(type default)
		)
	)
	(wire
		(pts
			(xy 63.5 60.96) (xy 50.8 60.96)
		)
		(stroke
			(width 0)
			(type default)
		)
	)
	(wire
		(pts
			(xy 157.48 226.06) (xy 157.48 264.16)
		)
		(stroke
			(width 0)
			(type default)
		)
	)
	(wire
		(pts
			(xy 158.75 130.81) (xy 176.53 130.81)
		)
		(stroke
			(width 0)
			(type default)
		)
	)
	(wire
		(pts
			(xy 318.77 143.51) (xy 318.77 149.86)
		)
		(stroke
			(width 0)
			(type default)
		)
	)
	(wire
		(pts
			(xy 168.91 274.32) (xy 168.91 275.59)
		)
		(stroke
			(width 0)
			(type default)
		)
	)
	(wire
		(pts
			(xy 374.65 38.1) (xy 377.19 38.1)
		)
		(stroke
			(width 0)
			(type default)
		)
	)
	(wire
		(pts
			(xy 53.34 238.76) (xy 53.34 240.03)
		)
		(stroke
			(width 0)
			(type default)
		)
	)
	(wire
		(pts
			(xy 199.39 271.78) (xy 199.39 274.32)
		)
		(stroke
			(width 0)
			(type default)
		)
	)
	(wire
		(pts
			(xy 148.59 252.73) (xy 148.59 247.65)
		)
		(stroke
			(width 0)
			(type default)
		)
	)
	(wire
		(pts
			(xy 119.38 229.87) (xy 119.38 234.95)
		)
		(stroke
			(width 0)
			(type default)
		)
	)
	(wire
		(pts
			(xy 231.14 133.35) (xy 255.27 133.35)
		)
		(stroke
			(width 0)
			(type default)
		)
	)
	(wire
		(pts
			(xy 72.39 240.03) (xy 80.01 240.03)
		)
		(stroke
			(width 0)
			(type default)
		)
	)
	(wire
		(pts
			(xy 177.8 85.09) (xy 194.31 85.09)
		)
		(stroke
			(width 0)
			(type default)
		)
	)
	(wire
		(pts
			(xy 105.41 102.87) (xy 92.71 102.87)
		)
		(stroke
			(width 0)
			(type default)
		)
	)
	(wire
		(pts
			(xy 92.71 143.51) (xy 78.74 143.51)
		)
		(stroke
			(width 0)
			(type default)
		)
	)
	(wire
		(pts
			(xy 255.27 64.77) (xy 252.73 64.77)
		)
		(stroke
			(width 0)
			(type default)
		)
	)
	(wire
		(pts
			(xy 368.3 134.62) (xy 383.54 134.62)
		)
		(stroke
			(width 0)
			(type default)
		)
	)
	(wire
		(pts
			(xy 265.43 228.6) (xy 284.48 228.6)
		)
		(stroke
			(width 0)
			(type default)
		)
	)
	(wire
		(pts
			(xy 359.41 40.64) (xy 373.38 40.64)
		)
		(stroke
			(width 0)
			(type default)
		)
	)
	(wire
		(pts
			(xy 179.07 171.45) (xy 179.07 176.53)
		)
		(stroke
			(width 0)
			(type default)
		)
	)
	(wire
		(pts
			(xy 252.73 110.49) (xy 252.73 102.87)
		)
		(stroke
			(width 0)
			(type default)
		)
	)
	(wire
		(pts
			(xy 337.82 229.87) (xy 341.63 229.87)
		)
		(stroke
			(width 0)
			(type default)
		)
	)
	(wire
		(pts
			(xy 147.32 166.37) (xy 147.32 168.91)
		)
		(stroke
			(width 0)
			(type default)
		)
	)
	(wire
		(pts
			(xy 177.8 39.37) (xy 194.31 39.37)
		)
		(stroke
			(width 0)
			(type default)
		)
	)
	(wire
		(pts
			(xy 96.52 267.97) (xy 96.52 269.24)
		)
		(stroke
			(width 0)
			(type default)
		)
	)
	(wire
		(pts
			(xy 147.32 153.67) (xy 170.18 153.67)
		)
		(stroke
			(width 0)
			(type default)
		)
	)
	(wire
		(pts
			(xy 92.71 171.45) (xy 78.74 171.45)
		)
		(stroke
			(width 0)
			(type default)
		)
	)
	(wire
		(pts
			(xy 118.11 52.07) (xy 105.41 52.07)
		)
		(stroke
			(width 0)
			(type default)
		)
	)
	(wire
		(pts
			(xy 368.3 204.47) (xy 368.3 214.63)
		)
		(stroke
			(width 0)
			(type default)
		)
	)
	(wire
		(pts
			(xy 370.84 80.01) (xy 370.84 45.72)
		)
		(stroke
			(width 0)
			(type default)
		)
	)
	(wire
		(pts
			(xy 185.42 115.57) (xy 194.31 115.57)
		)
		(stroke
			(width 0)
			(type default)
		)
	)
	(wire
		(pts
			(xy 337.82 232.41) (xy 368.3 232.41)
		)
		(stroke
			(width 0)
			(type default)
		)
	)
	(wire
		(pts
			(xy 295.91 128.27) (xy 318.77 128.27)
		)
		(stroke
			(width 0)
			(type default)
		)
	)
	(wire
		(pts
			(xy 363.22 50.8) (xy 363.22 48.26)
		)
		(stroke
			(width 0)
			(type default)
		)
	)
	(wire
		(pts
			(xy 299.72 52.07) (xy 300.99 52.07)
		)
		(stroke
			(width 0)
			(type default)
		)
	)
	(wire
		(pts
			(xy 237.49 85.09) (xy 255.27 85.09)
		)
		(stroke
			(width 0)
			(type default)
		)
	)
	(wire
		(pts
			(xy 96.52 274.32) (xy 96.52 276.86)
		)
		(stroke
			(width 0)
			(type default)
		)
	)
	(wire
		(pts
			(xy 297.18 209.55) (xy 297.18 210.82)
		)
		(stroke
			(width 0)
			(type default)
		)
	)
	(wire
		(pts
			(xy 191.77 163.83) (xy 194.31 163.83)
		)
		(stroke
			(width 0)
			(type default)
		)
	)
	(wire
		(pts
			(xy 157.48 222.25) (xy 157.48 226.06)
		)
		(stroke
			(width 0)
			(type default)
		)
	)
	(wire
		(pts
			(xy 191.77 80.01) (xy 191.77 102.87)
		)
		(stroke
			(width 0)
			(type default)
		)
	)
	(wire
		(pts
			(xy 265.43 233.68) (xy 265.43 228.6)
		)
		(stroke
			(width 0)
			(type default)
		)
	)
	(wire
		(pts
			(xy 177.8 46.99) (xy 194.31 46.99)
		)
		(stroke
			(width 0)
			(type default)
		)
	)
	(wire
		(pts
			(xy 63.5 35.56) (xy 50.8 35.56)
		)
		(stroke
			(width 0)
			(type default)
		)
	)
	(wire
		(pts
			(xy 314.96 217.17) (xy 312.42 217.17)
		)
		(stroke
			(width 0)
			(type default)
		)
	)
	(wire
		(pts
			(xy 246.38 54.61) (xy 255.27 54.61)
		)
		(stroke
			(width 0)
			(type default)
		)
	)
	(wire
		(pts
			(xy 157.48 123.19) (xy 176.53 123.19)
		)
		(stroke
			(width 0)
			(type default)
		)
	)
	(wire
		(pts
			(xy 118.11 41.91) (xy 105.41 41.91)
		)
		(stroke
			(width 0)
			(type default)
		)
	)
	(wire
		(pts
			(xy 53.34 227.33) (xy 53.34 229.87)
		)
		(stroke
			(width 0)
			(type default)
		)
	)
	(wire
		(pts
			(xy 311.15 59.69) (xy 312.42 59.69)
		)
		(stroke
			(width 0)
			(type default)
		)
	)
	(wire
		(pts
			(xy 177.8 100.33) (xy 194.31 100.33)
		)
		(stroke
			(width 0)
			(type default)
		)
	)
	(wire
		(pts
			(xy 118.11 58.42) (xy 105.41 58.42)
		)
		(stroke
			(width 0)
			(type default)
		)
	)
	(wire
		(pts
			(xy 264.16 231.14) (xy 264.16 226.06)
		)
		(stroke
			(width 0)
			(type default)
		)
	)
	(wire
		(pts
			(xy 165.1 234.95) (xy 165.1 237.49)
		)
		(stroke
			(width 0)
			(type default)
		)
	)
	(wire
		(pts
			(xy 359.41 38.1) (xy 374.65 38.1)
		)
		(stroke
			(width 0)
			(type default)
		)
	)
	(wire
		(pts
			(xy 92.71 163.83) (xy 78.74 163.83)
		)
		(stroke
			(width 0)
			(type default)
		)
	)
	(wire
		(pts
			(xy 356.87 52.07) (xy 360.68 52.07)
		)
		(stroke
			(width 0)
			(type default)
		)
	)
	(wire
		(pts
			(xy 308.61 204.47) (xy 308.61 219.71)
		)
		(stroke
			(width 0)
			(type default)
		)
	)
	(wire
		(pts
			(xy 252.73 163.83) (xy 252.73 166.37)
		)
		(stroke
			(width 0)
			(type default)
		)
	)
	(wire
		(pts
			(xy 105.41 236.22) (xy 102.87 236.22)
		)
		(stroke
			(width 0)
			(type default)
		)
	)
	(wire
		(pts
			(xy 63.5 58.42) (xy 50.8 58.42)
		)
		(stroke
			(width 0)
			(type default)
		)
	)
	(wire
		(pts
			(xy 63.5 39.37) (xy 50.8 39.37)
		)
		(stroke
			(width 0)
			(type default)
		)
	)
	(wire
		(pts
			(xy 40.64 210.82) (xy 44.45 210.82)
		)
		(stroke
			(width 0)
			(type default)
		)
	)
	(wire
		(pts
			(xy 92.71 168.91) (xy 78.74 168.91)
		)
		(stroke
			(width 0)
			(type default)
		)
	)
	(wire
		(pts
			(xy 158.75 140.97) (xy 176.53 140.97)
		)
		(stroke
			(width 0)
			(type default)
		)
	)
	(wire
		(pts
			(xy 252.73 102.87) (xy 255.27 102.87)
		)
		(stroke
			(width 0)
			(type default)
		)
	)
	(wire
		(pts
			(xy 148.59 214.63) (xy 157.48 214.63)
		)
		(stroke
			(width 0)
			(type default)
		)
	)
	(wire
		(pts
			(xy 306.07 133.35) (xy 306.07 138.43)
		)
		(stroke
			(width 0)
			(type default)
		)
	)
	(wire
		(pts
			(xy 369.57 82.55) (xy 369.57 48.26)
		)
		(stroke
			(width 0)
			(type default)
		)
	)
	(wire
		(pts
			(xy 135.89 153.67) (xy 147.32 153.67)
		)
		(stroke
			(width 0)
			(type default)
		)
	)
	(wire
		(pts
			(xy 92.71 166.37) (xy 78.74 166.37)
		)
		(stroke
			(width 0)
			(type default)
		)
	)
	(wire
		(pts
			(xy 246.38 44.45) (xy 255.27 44.45)
		)
		(stroke
			(width 0)
			(type default)
		)
	)
	(wire
		(pts
			(xy 53.34 229.87) (xy 71.12 229.87)
		)
		(stroke
			(width 0)
			(type default)
		)
	)
	(wire
		(pts
			(xy 199.39 226.06) (xy 199.39 228.6)
		)
		(stroke
			(width 0)
			(type default)
		)
	)
	(wire
		(pts
			(xy 105.41 90.17) (xy 92.71 90.17)
		)
		(stroke
			(width 0)
			(type default)
		)
	)
	(wire
		(pts
			(xy 255.27 80.01) (xy 252.73 80.01)
		)
		(stroke
			(width 0)
			(type default)
		)
	)
	(wire
		(pts
			(xy 177.8 82.55) (xy 194.31 82.55)
		)
		(stroke
			(width 0)
			(type default)
		)
	)
	(wire
		(pts
			(xy 59.69 240.03) (xy 71.12 240.03)
		)
		(stroke
			(width 0)
			(type default)
		)
	)
	(wire
		(pts
			(xy 193.04 234.95) (xy 193.04 228.6)
		)
		(stroke
			(width 0)
			(type default)
		)
	)
	(wire
		(pts
			(xy 158.75 158.75) (xy 158.75 161.29)
		)
		(stroke
			(width 0)
			(type default)
		)
	)
	(wire
		(pts
			(xy 191.77 110.49) (xy 191.77 163.83)
		)
		(stroke
			(width 0)
			(type default)
		)
	)
	(wire
		(pts
			(xy 189.23 133.35) (xy 189.23 130.81)
		)
		(stroke
			(width 0)
			(type default)
		)
	)
	(wire
		(pts
			(xy 189.23 156.21) (xy 189.23 153.67)
		)
		(stroke
			(width 0)
			(type default)
		)
	)
	(wire
		(pts
			(xy 337.82 234.95) (xy 383.54 234.95)
		)
		(stroke
			(width 0)
			(type default)
		)
	)
	(wire
		(pts
			(xy 40.64 200.66) (xy 40.64 210.82)
		)
		(stroke
			(width 0)
			(type default)
		)
	)
	(wire
		(pts
			(xy 368.3 138.43) (xy 368.3 134.62)
		)
		(stroke
			(width 0)
			(type default)
		)
	)
	(wire
		(pts
			(xy 337.82 217.17) (xy 342.9 217.17)
		)
		(stroke
			(width 0)
			(type default)
		)
	)
	(wire
		(pts
			(xy 185.42 120.65) (xy 194.31 120.65)
		)
		(stroke
			(width 0)
			(type default)
		)
	)
	(wire
		(pts
			(xy 78.74 233.68) (xy 85.09 233.68)
		)
		(stroke
			(width 0)
			(type default)
		)
	)
	(wire
		(pts
			(xy 246.38 62.23) (xy 255.27 62.23)
		)
		(stroke
			(width 0)
			(type default)
		)
	)
	(wire
		(pts
			(xy 191.77 72.39) (xy 191.77 80.01)
		)
		(stroke
			(width 0)
			(type default)
		)
	)
	(wire
		(pts
			(xy 237.49 97.79) (xy 255.27 97.79)
		)
		(stroke
			(width 0)
			(type default)
		)
	)
	(wire
		(pts
			(xy 105.41 97.79) (xy 92.71 97.79)
		)
		(stroke
			(width 0)
			(type default)
		)
	)
	(wire
		(pts
			(xy 158.75 143.51) (xy 176.53 143.51)
		)
		(stroke
			(width 0)
			(type default)
		)
	)
	(wire
		(pts
			(xy 177.8 95.25) (xy 194.31 95.25)
		)
		(stroke
			(width 0)
			(type default)
		)
	)
	(wire
		(pts
			(xy 237.49 87.63) (xy 255.27 87.63)
		)
		(stroke
			(width 0)
			(type default)
		)
	)
	(wire
		(pts
			(xy 111.76 90.17) (xy 111.76 91.44)
		)
		(stroke
			(width 0)
			(type default)
		)
	)
	(wire
		(pts
			(xy 181.61 143.51) (xy 189.23 143.51)
		)
		(stroke
			(width 0)
			(type default)
		)
	)
	(polyline
		(pts
			(xy 219.71 185.42) (xy 219.71 284.48)
		)
		(stroke
			(width 0)
			(type default)
		)
	)
	(wire
		(pts
			(xy 341.63 52.07) (xy 351.79 52.07)
		)
		(stroke
			(width 0)
			(type default)
		)
	)
	(wire
		(pts
			(xy 191.77 64.77) (xy 194.31 64.77)
		)
		(stroke
			(width 0)
			(type default)
		)
	)
	(wire
		(pts
			(xy 237.49 90.17) (xy 255.27 90.17)
		)
		(stroke
			(width 0)
			(type default)
		)
	)
	(wire
		(pts
			(xy 312.42 201.93) (xy 344.17 201.93)
		)
		(stroke
			(width 0)
			(type default)
		)
	)
	(wire
		(pts
			(xy 299.72 57.15) (xy 300.99 57.15)
		)
		(stroke
			(width 0)
			(type default)
		)
	)
	(wire
		(pts
			(xy 246.38 46.99) (xy 255.27 46.99)
		)
		(stroke
			(width 0)
			(type default)
		)
	)
	(wire
		(pts
			(xy 22.86 208.28) (xy 25.4 208.28)
		)
		(stroke
			(width 0)
			(type default)
		)
	)
	(wire
		(pts
			(xy 218.44 146.05) (xy 224.79 146.05)
		)
		(stroke
			(width 0)
			(type default)
		)
	)
	(wire
		(pts
			(xy 274.32 201.93) (xy 274.32 213.36)
		)
		(stroke
			(width 0)
			(type default)
		)
	)
	(wire
		(pts
			(xy 78.74 138.43) (xy 92.71 138.43)
		)
		(stroke
			(width 0)
			(type default)
		)
	)
	(wire
		(pts
			(xy 284.48 228.6) (xy 284.48 231.14)
		)
		(stroke
			(width 0)
			(type default)
		)
	)
	(wire
		(pts
			(xy 170.18 171.45) (xy 170.18 176.53)
		)
		(stroke
			(width 0)
			(type default)
		)
	)
	(wire
		(pts
			(xy 246.38 158.75) (xy 250.19 158.75)
		)
		(stroke
			(width 0)
			(type default)
		)
	)
	(wire
		(pts
			(xy 311.15 54.61) (xy 312.42 54.61)
		)
		(stroke
			(width 0)
			(type default)
		)
	)
	(wire
		(pts
			(xy 299.72 59.69) (xy 300.99 59.69)
		)
		(stroke
			(width 0)
			(type default)
		)
	)
	(wire
		(pts
			(xy 40.64 200.66) (xy 44.45 200.66)
		)
		(stroke
			(width 0)
			(type default)
		)
	)
	(wire
		(pts
			(xy 237.49 105.41) (xy 255.27 105.41)
		)
		(stroke
			(width 0)
			(type default)
		)
	)
	(wire
		(pts
			(xy 148.59 252.73) (xy 148.59 260.35)
		)
		(stroke
			(width 0)
			(type default)
		)
	)
	(wire
		(pts
			(xy 190.5 264.16) (xy 199.39 264.16)
		)
		(stroke
			(width 0)
			(type default)
		)
	)
	(wire
		(pts
			(xy 262.89 218.44) (xy 266.7 218.44)
		)
		(stroke
			(width 0)
			(type default)
		)
	)
	(wire
		(pts
			(xy 267.97 226.06) (xy 287.02 226.06)
		)
		(stroke
			(width 0)
			(type default)
		)
	)
	(wire
		(pts
			(xy 111.76 80.01) (xy 111.76 85.09)
		)
		(stroke
			(width 0)
			(type default)
		)
	)
	(wire
		(pts
			(xy 78.74 125.73) (xy 114.3 125.73)
		)
		(stroke
			(width 0)
			(type default)
		)
	)
	(wire
		(pts
			(xy 200.66 260.35) (xy 190.5 260.35)
		)
		(stroke
			(width 0)
			(type default)
		)
	)
	(polyline
		(pts
			(xy 274.32 185.42) (xy 407.67 185.42)
		)
		(stroke
			(width 0)
			(type default)
		)
	)
	(wire
		(pts
			(xy 148.59 214.63) (xy 148.59 222.25)
		)
		(stroke
			(width 0)
			(type default)
		)
	)
	(wire
		(pts
			(xy 236.22 143.51) (xy 236.22 138.43)
		)
		(stroke
			(width 0)
			(type default)
		)
	)
	(wire
		(pts
			(xy 40.64 210.82) (xy 40.64 213.36)
		)
		(stroke
			(width 0)
			(type default)
		)
	)
	(wire
		(pts
			(xy 102.87 233.68) (xy 110.49 233.68)
		)
		(stroke
			(width 0)
			(type default)
		)
	)
	(wire
		(pts
			(xy 185.42 113.03) (xy 185.42 115.57)
		)
		(stroke
			(width 0)
			(type default)
		)
	)
	(wire
		(pts
			(xy 383.54 134.62) (xy 383.54 140.97)
		)
		(stroke
			(width 0)
			(type default)
		)
	)
	(wire
		(pts
			(xy 359.41 45.72) (xy 360.68 45.72)
		)
		(stroke
			(width 0)
			(type default)
		)
	)
	(wire
		(pts
			(xy 168.91 266.7) (xy 168.91 269.24)
		)
		(stroke
			(width 0)
			(type default)
		)
	)
	(wire
		(pts
			(xy 191.77 102.87) (xy 194.31 102.87)
		)
		(stroke
			(width 0)
			(type default)
		)
	)
	(wire
		(pts
			(xy 365.76 143.51) (xy 369.57 143.51)
		)
		(stroke
			(width 0)
			(type default)
		)
	)
	(wire
		(pts
			(xy 189.23 161.29) (xy 194.31 161.29)
		)
		(stroke
			(width 0)
			(type default)
		)
	)
	(wire
		(pts
			(xy 383.54 204.47) (xy 383.54 214.63)
		)
		(stroke
			(width 0)
			(type default)
		)
	)
	(wire
		(pts
			(xy 238.76 140.97) (xy 255.27 140.97)
		)
		(stroke
			(width 0)
			(type default)
		)
	)
	(wire
		(pts
			(xy 229.87 146.05) (xy 238.76 146.05)
		)
		(stroke
			(width 0)
			(type default)
		)
	)
	(wire
		(pts
			(xy 177.8 97.79) (xy 194.31 97.79)
		)
		(stroke
			(width 0)
			(type default)
		)
	)
	(wire
		(pts
			(xy 158.75 158.75) (xy 179.07 158.75)
		)
		(stroke
			(width 0)
			(type default)
		)
	)
	(wire
		(pts
			(xy 179.07 158.75) (xy 189.23 158.75)
		)
		(stroke
			(width 0)
			(type default)
		)
	)
	(wire
		(pts
			(xy 381 82.55) (xy 369.57 82.55)
		)
		(stroke
			(width 0)
			(type default)
		)
	)
	(wire
		(pts
			(xy 177.8 92.71) (xy 194.31 92.71)
		)
		(stroke
			(width 0)
			(type default)
		)
	)
	(wire
		(pts
			(xy 157.48 214.63) (xy 165.1 214.63)
		)
		(stroke
			(width 0)
			(type default)
		)
	)
	(wire
		(pts
			(xy 118.11 54.61) (xy 105.41 54.61)
		)
		(stroke
			(width 0)
			(type default)
		)
	)
	(wire
		(pts
			(xy 135.89 158.75) (xy 158.75 158.75)
		)
		(stroke
			(width 0)
			(type default)
		)
	)
	(wire
		(pts
			(xy 158.75 133.35) (xy 176.53 133.35)
		)
		(stroke
			(width 0)
			(type default)
		)
	)
	(wire
		(pts
			(xy 80.01 179.07) (xy 78.74 179.07)
		)
		(stroke
			(width 0)
			(type default)
		)
	)
	(wire
		(pts
			(xy 95.25 151.13) (xy 78.74 151.13)
		)
		(stroke
			(width 0)
			(type default)
		)
	)
	(wire
		(pts
			(xy 105.41 100.33) (xy 92.71 100.33)
		)
		(stroke
			(width 0)
			(type default)
		)
	)
	(wire
		(pts
			(xy 179.07 158.75) (xy 179.07 166.37)
		)
		(stroke
			(width 0)
			(type default)
		)
	)
	(wire
		(pts
			(xy 284.48 228.6) (xy 287.02 228.6)
		)
		(stroke
			(width 0)
			(type default)
		)
	)
	(wire
		(pts
			(xy 383.54 219.71) (xy 383.54 224.79)
		)
		(stroke
			(width 0)
			(type default)
		)
	)
	(wire
		(pts
			(xy 218.44 133.35) (xy 226.06 133.35)
		)
		(stroke
			(width 0)
			(type default)
		)
	)
	(wire
		(pts
			(xy 241.3 123.19) (xy 245.11 123.19)
		)
		(stroke
			(width 0)
			(type default)
		)
	)
	(wire
		(pts
			(xy 252.73 80.01) (xy 252.73 102.87)
		)
		(stroke
			(width 0)
			(type default)
		)
	)
	(wire
		(pts
			(xy 172.72 266.7) (xy 168.91 266.7)
		)
		(stroke
			(width 0)
			(type default)
		)
	)
	(wire
		(pts
			(xy 264.16 250.19) (xy 264.16 248.92)
		)
		(stroke
			(width 0)
			(type default)
		)
	)
	(wire
		(pts
			(xy 118.11 45.72) (xy 105.41 45.72)
		)
		(stroke
			(width 0)
			(type default)
		)
	)
	(wire
		(pts
			(xy 186.69 135.89) (xy 194.31 135.89)
		)
		(stroke
			(width 0)
			(type default)
		)
	)
	(wire
		(pts
			(xy 292.1 226.06) (xy 314.96 226.06)
		)
		(stroke
			(width 0)
			(type default)
		)
	)
	(wire
		(pts
			(xy 246.38 36.83) (xy 255.27 36.83)
		)
		(stroke
			(width 0)
			(type default)
		)
	)
	(wire
		(pts
			(xy 278.13 220.98) (xy 278.13 218.44)
		)
		(stroke
			(width 0)
			(type default)
		)
	)
	(wire
		(pts
			(xy 105.41 87.63) (xy 92.71 87.63)
		)
		(stroke
			(width 0)
			(type default)
		)
	)
	(wire
		(pts
			(xy 237.49 100.33) (xy 255.27 100.33)
		)
		(stroke
			(width 0)
			(type default)
		)
	)
	(wire
		(pts
			(xy 342.9 35.56) (xy 347.98 35.56)
		)
		(stroke
			(width 0)
			(type default)
		)
	)
	(wire
		(pts
			(xy 177.8 54.61) (xy 194.31 54.61)
		)
		(stroke
			(width 0)
			(type default)
		)
	)
	(wire
		(pts
			(xy 382.27 143.51) (xy 383.54 143.51)
		)
		(stroke
			(width 0)
			(type default)
		)
	)
	(wire
		(pts
			(xy 186.69 138.43) (xy 194.31 138.43)
		)
		(stroke
			(width 0)
			(type default)
		)
	)
	(wire
		(pts
			(xy 158.75 173.99) (xy 158.75 176.53)
		)
		(stroke
			(width 0)
			(type default)
		)
	)
	(wire
		(pts
			(xy 148.59 252.73) (xy 165.1 252.73)
		)
		(stroke
			(width 0)
			(type default)
		)
	)
	(wire
		(pts
			(xy 308.61 219.71) (xy 308.61 222.25)
		)
		(stroke
			(width 0)
			(type default)
		)
	)
	(wire
		(pts
			(xy 215.9 118.11) (xy 236.22 118.11)
		)
		(stroke
			(width 0)
			(type default)
		)
	)
	(wire
		(pts
			(xy 264.16 248.92) (xy 264.16 246.38)
		)
		(stroke
			(width 0)
			(type default)
		)
	)
	(wire
		(pts
			(xy 102.87 229.87) (xy 119.38 229.87)
		)
		(stroke
			(width 0)
			(type default)
		)
	)
	(wire
		(pts
			(xy 262.89 220.98) (xy 266.7 220.98)
		)
		(stroke
			(width 0)
			(type default)
		)
	)
	(wire
		(pts
			(xy 119.38 240.03) (xy 119.38 243.84)
		)
		(stroke
			(width 0)
			(type default)
		)
	)
	(wire
		(pts
			(xy 250.19 158.75) (xy 255.27 158.75)
		)
		(stroke
			(width 0)
			(type default)
		)
	)
	(wire
		(pts
			(xy 311.15 62.23) (xy 312.42 62.23)
		)
		(stroke
			(width 0)
			(type default)
		)
	)
	(wire
		(pts
			(xy 368.3 204.47) (xy 383.54 204.47)
		)
		(stroke
			(width 0)
			(type default)
		)
	)
	(wire
		(pts
			(xy 177.8 105.41) (xy 194.31 105.41)
		)
		(stroke
			(width 0)
			(type default)
		)
	)
	(wire
		(pts
			(xy 71.12 237.49) (xy 71.12 240.03)
		)
		(stroke
			(width 0)
			(type default)
		)
	)
	(wire
		(pts
			(xy 114.3 121.92) (xy 114.3 125.73)
		)
		(stroke
			(width 0)
			(type default)
		)
	)
	(wire
		(pts
			(xy 238.76 146.05) (xy 238.76 140.97)
		)
		(stroke
			(width 0)
			(type default)
		)
	)
	(wire
		(pts
			(xy 193.04 274.32) (xy 193.04 266.7)
		)
		(stroke
			(width 0)
			(type default)
		)
	)
	(label "MIPI0_CLK_N"
		(at 63.5 35.56 180)
		(effects
			(font
				(size 1.27 1.27)
			)
			(justify right bottom)
		)
	)
	(label "FFC1_5V"
		(at 200.66 260.35 180)
		(effects
			(font
				(size 1.27 1.27)
			)
			(justify right bottom)
		)
	)
	(label "FFC2_VSYNC0"
		(at 92.71 130.81 180)
		(effects
			(font
				(size 1.27 1.27)
			)
			(justify right bottom)
		)
	)
	(label "MIPI2_D2_P"
		(at 105.41 92.71 180)
		(effects
			(font
				(size 1.27 1.27)
			)
			(justify right bottom)
		)
	)
	(label "MIPI2_CLK_N"
		(at 105.41 105.41 180)
		(effects
			(font
				(size 1.27 1.27)
			)
			(justify right bottom)
		)
	)
	(label "3V3_MISC"
		(at 361.95 35.56 0)
		(effects
			(font
				(size 1.27 1.27)
			)
			(justify left bottom)
		)
	)
	(label "MIPI2_CLK_P"
		(at 177.8 107.95 0)
		(effects
			(font
				(size 1.27 1.27)
			)
			(justify left bottom)
		)
	)
	(label "MIPI2_D1_P"
		(at 105.41 87.63 180)
		(effects
			(font
				(size 1.27 1.27)
			)
			(justify right bottom)
		)
	)
	(label "MIPI2_D1_N"
		(at 177.8 92.71 0)
		(effects
			(font
				(size 1.27 1.27)
			)
			(justify left bottom)
		)
	)
	(label "MIPI2_D1_N"
		(at 105.41 90.17 180)
		(effects
			(font
				(size 1.27 1.27)
			)
			(justify right bottom)
		)
	)
	(label "MIPI0_CLK_N"
		(at 177.8 59.69 0)
		(effects
			(font
				(size 1.27 1.27)
			)
			(justify left bottom)
		)
	)
	(label "MIPI0_D2_N"
		(at 177.8 41.91 0)
		(effects
			(font
				(size 1.27 1.27)
			)
			(justify left bottom)
		)
	)
	(label "FTDI_VCCIO"
		(at 316.23 204.47 0)
		(effects
			(font
				(size 1.27 1.27)
			)
			(justify left bottom)
		)
	)
	(label "FFC1_VSYNC1"
		(at 157.48 123.19 0)
		(effects
			(font
				(size 1.27 1.27)
			)
			(justify left bottom)
		)
	)
	(label "MIPI1_D1_P"
		(at 237.49 95.25 0)
		(effects
			(font
				(size 1.27 1.27)
			)
			(justify left bottom)
		)
	)
	(label "FFC1_VSYNC0"
		(at 92.71 173.99 180)
		(effects
			(font
				(size 1.27 1.27)
			)
			(justify right bottom)
		)
	)
	(label "MIPI0_D2_N"
		(at 63.5 54.61 180)
		(effects
			(font
				(size 1.27 1.27)
			)
			(justify right bottom)
		)
	)
	(label "MIPI0_D2_P"
		(at 63.5 52.07 180)
		(effects
			(font
				(size 1.27 1.27)
			)
			(justify right bottom)
		)
	)
	(label "FFC1_5V"
		(at 135.89 158.75 0)
		(effects
			(font
				(size 1.27 1.27)
			)
			(justify left bottom)
		)
	)
	(label "FCC1_SDA1"
		(at 158.75 130.81 0)
		(effects
			(font
				(size 1.27 1.27)
			)
			(justify left bottom)
		)
	)
	(label "MIPI1_D1_N"
		(at 118.11 48.26 180)
		(effects
			(font
				(size 1.27 1.27)
			)
			(justify right bottom)
		)
	)
	(label "FCC2_SDA2"
		(at 92.71 148.59 180)
		(effects
			(font
				(size 1.27 1.27)
			)
			(justify right bottom)
		)
	)
	(label "MIPI2_D3_P"
		(at 177.8 85.09 0)
		(effects
			(font
				(size 1.27 1.27)
			)
			(justify left bottom)
		)
	)
	(label "MIPI2_D3_N"
		(at 177.8 82.55 0)
		(effects
			(font
				(size 1.27 1.27)
			)
			(justify left bottom)
		)
	)
	(label "QWIIC_PEN"
		(at 341.63 52.07 0)
		(effects
			(font
				(size 1.27 1.27)
			)
			(justify left bottom)
		)
	)
	(label "FFC1_RESET"
		(at 157.48 118.11 0)
		(effects
			(font
				(size 1.27 1.27)
			)
			(justify left bottom)
		)
	)
	(label "FFC2_RESET"
		(at 215.9 118.11 0)
		(effects
			(font
				(size 1.27 1.27)
			)
			(justify left bottom)
		)
	)
	(label "USB_D2P"
		(at 298.45 226.06 0)
		(effects
			(font
				(size 1.27 1.27)
			)
			(justify left bottom)
		)
	)
	(label "FFC2_VSYNC0"
		(at 215.9 113.03 0)
		(effects
			(font
				(size 1.27 1.27)
			)
			(justify left bottom)
		)
	)
	(label "FCC1_SDA2"
		(at 158.75 140.97 0)
		(effects
			(font
				(size 1.27 1.27)
			)
			(justify left bottom)
		)
	)
	(label "MIPI0_D3_N"
		(at 177.8 36.83 0)
		(effects
			(font
				(size 1.27 1.27)
			)
			(justify left bottom)
		)
	)
	(label "MIPI1_D3_N"
		(at 118.11 60.96 180)
		(effects
			(font
				(size 1.27 1.27)
			)
			(justify right bottom)
		)
	)
	(label "FCC1_SCL1"
		(at 92.71 166.37 180)
		(effects
			(font
				(size 1.27 1.27)
			)
			(justify right bottom)
		)
	)
	(label "MIPI2_D2_N"
		(at 105.41 95.25 180)
		(effects
			(font
				(size 1.27 1.27)
			)
			(justify right bottom)
		)
	)
	(label "FCC1_SCL1"
		(at 158.75 133.35 0)
		(effects
			(font
				(size 1.27 1.27)
			)
			(justify left bottom)
		)
	)
	(label "FFC1_3V3"
		(at 200.66 222.25 180)
		(effects
			(font
				(size 1.27 1.27)
			)
			(justify right bottom)
		)
	)
	(label "MIPI0_D0_P"
		(at 177.8 54.61 0)
		(effects
			(font
				(size 1.27 1.27)
			)
			(justify left bottom)
		)
	)
	(label "MIPI0_D1_P"
		(at 63.5 45.72 180)
		(effects
			(font
				(size 1.27 1.27)
			)
			(justify right bottom)
		)
	)
	(label "MIPI0_D3_N"
		(at 63.5 60.96 180)
		(effects
			(font
				(size 1.27 1.27)
			)
			(justify right bottom)
		)
	)
	(label "MIPI0_D0_N"
		(at 63.5 41.91 180)
		(effects
			(font
				(size 1.27 1.27)
			)
			(justify right bottom)
		)
	)
	(label "MIPI1_D2_N"
		(at 118.11 54.61 180)
		(effects
			(font
				(size 1.27 1.27)
			)
			(justify right bottom)
		)
	)
	(label "QW_FLT"
		(at 106.68 276.86 180)
		(effects
			(font
				(size 1.27 1.27)
			)
			(justify right bottom)
		)
	)
	(label "MIPI1_D2_P"
		(at 237.49 90.17 0)
		(effects
			(font
				(size 1.27 1.27)
			)
			(justify left bottom)
		)
	)
	(label "MIPI1_D1_N"
		(at 237.49 92.71 0)
		(effects
			(font
				(size 1.27 1.27)
			)
			(justify left bottom)
		)
	)
	(label "USB_D2N"
		(at 298.45 228.6 0)
		(effects
			(font
				(size 1.27 1.27)
			)
			(justify left bottom)
		)
	)
	(label "MIPI1_D3_P"
		(at 237.49 85.09 0)
		(effects
			(font
				(size 1.27 1.27)
			)
			(justify left bottom)
		)
	)
	(label "MIPI2_D3_P"
		(at 105.41 97.79 180)
		(effects
			(font
				(size 1.27 1.27)
			)
			(justify right bottom)
		)
	)
	(label "MIPI1_D3_N"
		(at 237.49 82.55 0)
		(effects
			(font
				(size 1.27 1.27)
			)
			(justify left bottom)
		)
	)
	(label "MIPI2_D0_N"
		(at 105.41 85.09 180)
		(effects
			(font
				(size 1.27 1.27)
			)
			(justify right bottom)
		)
	)
	(label "FCC1_SDA2"
		(at 92.71 168.91 180)
		(effects
			(font
				(size 1.27 1.27)
			)
			(justify right bottom)
		)
	)
	(label "MIPI1_D2_N"
		(at 237.49 87.63 0)
		(effects
			(font
				(size 1.27 1.27)
			)
			(justify left bottom)
		)
	)
	(label "MIPI2_D2_P"
		(at 177.8 90.17 0)
		(effects
			(font
				(size 1.27 1.27)
			)
			(justify left bottom)
		)
	)
	(label "MIPI0_D3_P"
		(at 63.5 58.42 180)
		(effects
			(font
				(size 1.27 1.27)
			)
			(justify right bottom)
		)
	)
	(label "MIPI2_CLK_N"
		(at 177.8 105.41 0)
		(effects
			(font
				(size 1.27 1.27)
			)
			(justify left bottom)
		)
	)
	(label "FFC1_PEN"
		(at 158.75 241.3 0)
		(effects
			(font
				(size 1.27 1.27)
			)
			(justify left bottom)
		)
	)
	(label "MIPI2_D0_N"
		(at 177.8 97.79 0)
		(effects
			(font
				(size 1.27 1.27)
			)
			(justify left bottom)
		)
	)
	(label "MIPI2_D1_P"
		(at 177.8 95.25 0)
		(effects
			(font
				(size 1.27 1.27)
			)
			(justify left bottom)
		)
	)
	(label "MIPI0_D1_N"
		(at 63.5 48.26 180)
		(effects
			(font
				(size 1.27 1.27)
			)
			(justify right bottom)
		)
	)
	(label "QWIIC_PEN"
		(at 59.69 240.03 0)
		(effects
			(font
				(size 1.27 1.27)
			)
			(justify left bottom)
		)
	)
	(label "FFC1_RESET"
		(at 92.71 143.51 180)
		(effects
			(font
				(size 1.27 1.27)
			)
			(justify right bottom)
		)
	)
	(label "FCC1_SDA1"
		(at 92.71 163.83 180)
		(effects
			(font
				(size 1.27 1.27)
			)
			(justify right bottom)
		)
	)
	(label "QWIIC_3V3"
		(at 22.86 198.12 0)
		(effects
			(font
				(size 1.27 1.27)
			)
			(justify left bottom)
		)
	)
	(label "MIPI1_CLK_P"
		(at 237.49 107.95 0)
		(effects
			(font
				(size 1.27 1.27)
			)
			(justify left bottom)
		)
	)
	(label "MIPI0_D1_P"
		(at 177.8 49.53 0)
		(effects
			(font
				(size 1.27 1.27)
			)
			(justify left bottom)
		)
	)
	(label "MIPI1_D0_P"
		(at 237.49 100.33 0)
		(effects
			(font
				(size 1.27 1.27)
			)
			(justify left bottom)
		)
	)
	(label "MIPI2_D0_P"
		(at 105.41 82.55 180)
		(effects
			(font
				(size 1.27 1.27)
			)
			(justify right bottom)
		)
	)
	(label "MIPI0_D2_P"
		(at 177.8 44.45 0)
		(effects
			(font
				(size 1.27 1.27)
			)
			(justify left bottom)
		)
	)
	(label "MIPI0_CLK_P"
		(at 63.5 33.02 180)
		(effects
			(font
				(size 1.27 1.27)
			)
			(justify right bottom)
		)
	)
	(label "MIPI1_CLK_N"
		(at 118.11 35.56 180)
		(effects
			(font
				(size 1.27 1.27)
			)
			(justify right bottom)
		)
	)
	(label "FFC2_3V3"
		(at 240.03 153.67 0)
		(effects
			(font
				(size 1.27 1.27)
			)
			(justify left bottom)
		)
	)
	(label "MIPI1_CLK_P"
		(at 118.11 33.02 180)
		(effects
			(font
				(size 1.27 1.27)
			)
			(justify right bottom)
		)
	)
	(label "USB_DN"
		(at 269.24 228.6 0)
		(effects
			(font
				(size 1.27 1.27)
			)
			(justify left bottom)
		)
	)
	(label "QWIIC_3V3"
		(at 78.74 196.85 0)
		(effects
			(font
				(size 1.27 1.27)
			)
			(justify left bottom)
		)
	)
	(label "FFC2_VSYNC1"
		(at 215.9 123.19 0)
		(effects
			(font
				(size 1.27 1.27)
			)
			(justify left bottom)
		)
	)
	(label "MIPI0_D0_P"
		(at 63.5 39.37 180)
		(effects
			(font
				(size 1.27 1.27)
			)
			(justify right bottom)
		)
	)
	(label "USB_DP"
		(at 269.24 226.06 0)
		(effects
			(font
				(size 1.27 1.27)
			)
			(justify left bottom)
		)
	)
	(label "MIPI2_CLK_P"
		(at 105.41 102.87 180)
		(effects
			(font
				(size 1.27 1.27)
			)
			(justify right bottom)
		)
	)
	(label "MIPI1_D1_P"
		(at 118.11 45.72 180)
		(effects
			(font
				(size 1.27 1.27)
			)
			(justify right bottom)
		)
	)
	(label "MIPI0_D1_N"
		(at 177.8 46.99 0)
		(effects
			(font
				(size 1.27 1.27)
			)
			(justify left bottom)
		)
	)
	(label "MIPI0_D3_P"
		(at 177.8 39.37 0)
		(effects
			(font
				(size 1.27 1.27)
			)
			(justify left bottom)
		)
	)
	(label "FCC1_SCL2"
		(at 92.71 171.45 180)
		(effects
			(font
				(size 1.27 1.27)
			)
			(justify right bottom)
		)
	)
	(label "FFC1_VSYNC0"
		(at 157.48 113.03 0)
		(effects
			(font
				(size 1.27 1.27)
			)
			(justify left bottom)
		)
	)
	(label "FCC2_SDA2"
		(at 207.01 143.51 0)
		(effects
			(font
				(size 1.27 1.27)
			)
			(justify left bottom)
		)
	)
	(label "MIPI1_D3_P"
		(at 118.11 58.42 180)
		(effects
			(font
				(size 1.27 1.27)
			)
			(justify right bottom)
		)
	)
	(label "FCC1_SCL2"
		(at 158.75 143.51 0)
		(effects
			(font
				(size 1.27 1.27)
			)
			(justify left bottom)
		)
	)
	(label "FFC1_VSYNC1"
		(at 92.71 176.53 180)
		(effects
			(font
				(size 1.27 1.27)
			)
			(justify right bottom)
		)
	)
	(label "FFC1_3V3"
		(at 135.89 153.67 0)
		(effects
			(font
				(size 1.27 1.27)
			)
			(justify left bottom)
		)
	)
	(label "MIPI1_CLK_N"
		(at 237.49 105.41 0)
		(effects
			(font
				(size 1.27 1.27)
			)
			(justify left bottom)
		)
	)
	(label "MIPI2_D0_P"
		(at 177.8 100.33 0)
		(effects
			(font
				(size 1.27 1.27)
			)
			(justify left bottom)
		)
	)
	(label "MIPI1_D0_N"
		(at 237.49 97.79 0)
		(effects
			(font
				(size 1.27 1.27)
			)
			(justify left bottom)
		)
	)
	(label "FFC2_RESET"
		(at 92.71 133.35 180)
		(effects
			(font
				(size 1.27 1.27)
			)
			(justify right bottom)
		)
	)
	(label "MIPI0_D0_N"
		(at 177.8 52.07 0)
		(effects
			(font
				(size 1.27 1.27)
			)
			(justify left bottom)
		)
	)
	(label "MIPI0_CLK_P"
		(at 177.8 62.23 0)
		(effects
			(font
				(size 1.27 1.27)
			)
			(justify left bottom)
		)
	)
	(label "MIPI1_D2_P"
		(at 118.11 52.07 180)
		(effects
			(font
				(size 1.27 1.27)
			)
			(justify right bottom)
		)
	)
	(label "QWIIC_3V3"
		(at 129.54 229.87 180)
		(effects
			(font
				(size 1.27 1.27)
			)
			(justify right bottom)
		)
	)
	(label "QW_FLT"
		(at 78.74 233.68 0)
		(effects
			(font
				(size 1.27 1.27)
			)
			(justify left bottom)
		)
	)
	(label "FFC2_VSYNC1"
		(at 92.71 135.89 180)
		(effects
			(font
				(size 1.27 1.27)
			)
			(justify right bottom)
		)
	)
	(label "MIPI2_D3_N"
		(at 105.41 100.33 180)
		(effects
			(font
				(size 1.27 1.27)
			)
			(justify right bottom)
		)
	)
	(label "MIPI1_D0_N"
		(at 118.11 41.91 180)
		(effects
			(font
				(size 1.27 1.27)
			)
			(justify right bottom)
		)
	)
	(label "MIPI2_D2_N"
		(at 177.8 87.63 0)
		(effects
			(font
				(size 1.27 1.27)
			)
			(justify left bottom)
		)
	)
	(label "FFC1_PEN"
		(at 92.71 138.43 180)
		(effects
			(font
				(size 1.27 1.27)
			)
			(justify right bottom)
		)
	)
	(label "MIPI1_D0_P"
		(at 118.11 39.37 180)
		(effects
			(font
				(size 1.27 1.27)
			)
			(justify right bottom)
		)
	)
	(global_label "SCL"
		(shape input)
		(at 22.86 208.28 180)
		(fields_autoplaced yes)
		(effects
			(font
				(size 1.27 1.27)
			)
			(justify right)
		)
		(property "Intersheetrefs" "${INTERSHEET_REFS}"
			(at 16.9393 208.2006 0)
			(effects
				(font
					(size 1.27 1.27)
				)
				(justify right)
				(hide yes)
			)
		)
	)
	(global_label "FCC2_SCL2"
		(shape input)
		(at 218.44 146.05 180)
		(fields_autoplaced yes)
		(effects
			(font
				(size 1.27 1.27)
			)
			(justify right)
		)
		(property "Intersheetrefs" "${INTERSHEET_REFS}"
			(at 205.504 145.9706 0)
			(effects
				(font
					(size 1.27 1.27)
				)
				(justify right)
				(hide yes)
			)
		)
	)
	(global_label "GPIO1"
		(shape input)
		(at 359.41 40.64 180)
		(fields_autoplaced yes)
		(effects
			(font
				(size 1.27 1.27)
			)
			(justify right)
		)
		(property "Intersheetrefs" "${INTERSHEET_REFS}"
			(at 351.3121 40.5606 0)
			(effects
				(font
					(size 1.27 1.27)
				)
				(justify right)
				(hide yes)
			)
		)
	)
	(global_label "SDA"
		(shape input)
		(at 22.86 205.74 180)
		(fields_autoplaced yes)
		(effects
			(font
				(size 1.27 1.27)
			)
			(justify right)
		)
		(property "Intersheetrefs" "${INTERSHEET_REFS}"
			(at 16.8788 205.6606 0)
			(effects
				(font
					(size 1.27 1.27)
				)
				(justify right)
				(hide yes)
			)
		)
	)
	(global_label "AUDIO_OUT_CH3_4"
		(shape input)
		(at 299.72 59.69 180)
		(fields_autoplaced yes)
		(effects
			(font
				(size 1.27 1.27)
			)
			(justify right)
		)
		(property "Intersheetrefs" "${INTERSHEET_REFS}"
			(at 280.1317 59.6106 0)
			(effects
				(font
					(size 1.27 1.27)
				)
				(justify right)
				(hide yes)
			)
		)
	)
	(global_label "DIP0"
		(shape input)
		(at 365.76 140.97 180)
		(fields_autoplaced yes)
		(effects
			(font
				(size 1.27 1.27)
			)
			(justify right)
		)
		(property "Intersheetrefs" "${INTERSHEET_REFS}"
			(at 358.9926 140.8906 0)
			(effects
				(font
					(size 1.27 1.27)
				)
				(justify right)
				(hide yes)
			)
		)
	)
	(global_label "SCL"
		(shape input)
		(at 218.44 135.89 180)
		(fields_autoplaced yes)
		(effects
			(font
				(size 1.27 1.27)
			)
			(justify right)
		)
		(property "Intersheetrefs" "${INTERSHEET_REFS}"
			(at 212.5193 135.8106 0)
			(effects
				(font
					(size 1.27 1.27)
				)
				(justify right)
				(hide yes)
			)
		)
	)
	(global_label "AUDIO_WCLK"
		(shape input)
		(at 299.72 54.61 180)
		(fields_autoplaced yes)
		(effects
			(font
				(size 1.27 1.27)
			)
			(justify right)
		)
		(property "Intersheetrefs" "${INTERSHEET_REFS}"
			(at 285.6955 54.5306 0)
			(effects
				(font
					(size 1.27 1.27)
				)
				(justify right)
				(hide yes)
			)
		)
	)
	(global_label "AUDIO_OUT_CH5_6"
		(shape input)
		(at 312.42 57.15 0)
		(fields_autoplaced yes)
		(effects
			(font
				(size 1.27 1.27)
			)
			(justify left)
		)
		(property "Intersheetrefs" "${INTERSHEET_REFS}"
			(at 332.0083 57.0706 0)
			(effects
				(font
					(size 1.27 1.27)
				)
				(justify left)
				(hide yes)
			)
		)
	)
	(global_label "RXD"
		(shape input)
		(at 342.9 219.71 0)
		(fields_autoplaced yes)
		(effects
			(font
				(size 1.27 1.27)
			)
			(justify left)
		)
		(property "Intersheetrefs" "${INTERSHEET_REFS}"
			(at 349.0626 219.6306 0)
			(effects
				(font
					(size 1.27 1.27)
				)
				(justify left)
				(hide yes)
			)
		)
	)
	(global_label "JTAG_EN"
		(shape input)
		(at 95.25 128.27 0)
		(fields_autoplaced yes)
		(effects
			(font
				(size 1.27 1.27)
			)
			(justify left)
		)
		(property "Intersheetrefs" "${INTERSHEET_REFS}"
			(at 105.4041 128.1906 0)
			(effects
				(font
					(size 1.27 1.27)
				)
				(justify left)
				(hide yes)
			)
		)
	)
	(global_label "FFC2_5V"
		(shape input)
		(at 246.38 158.75 180)
		(fields_autoplaced yes)
		(effects
			(font
				(size 1.27 1.27)
			)
			(justify right)
		)
		(property "Intersheetrefs" "${INTERSHEET_REFS}"
			(at 236.0445 158.6706 0)
			(effects
				(font
					(size 1.27 1.27)
				)
				(justify right)
				(hide yes)
			)
		)
	)
	(global_label "TDO"
		(shape input)
		(at 95.25 151.13 0)
		(fields_autoplaced yes)
		(effects
			(font
				(size 1.27 1.27)
			)
			(justify left)
		)
		(property "Intersheetrefs" "${INTERSHEET_REFS}"
			(at 101.2312 151.0506 0)
			(effects
				(font
					(size 1.27 1.27)
				)
				(justify left)
				(hide yes)
			)
		)
	)
	(global_label "AUDIO_ACLK"
		(shape input)
		(at 312.42 52.07 0)
		(fields_autoplaced yes)
		(effects
			(font
				(size 1.27 1.27)
			)
			(justify left)
		)
		(property "Intersheetrefs" "${INTERSHEET_REFS}"
			(at 326.0817 51.9906 0)
			(effects
				(font
					(size 1.27 1.27)
				)
				(justify left)
				(hide yes)
			)
		)
	)
	(global_label "AUDIO_OUT_CH1_2"
		(shape input)
		(at 299.72 57.15 180)
		(fields_autoplaced yes)
		(effects
			(font
				(size 1.27 1.27)
			)
			(justify right)
		)
		(property "Intersheetrefs" "${INTERSHEET_REFS}"
			(at 280.1317 57.0706 0)
			(effects
				(font
					(size 1.27 1.27)
				)
				(justify right)
				(hide yes)
			)
		)
	)
	(global_label "GPIO0"
		(shape input)
		(at 359.41 38.1 180)
		(fields_autoplaced yes)
		(effects
			(font
				(size 1.27 1.27)
			)
			(justify right)
		)
		(property "Intersheetrefs" "${INTERSHEET_REFS}"
			(at 351.3121 38.0206 0)
			(effects
				(font
					(size 1.27 1.27)
				)
				(justify right)
				(hide yes)
			)
		)
	)
	(global_label "AUDIO_ACLK"
		(shape input)
		(at 299.72 52.07 180)
		(fields_autoplaced yes)
		(effects
			(font
				(size 1.27 1.27)
			)
			(justify right)
		)
		(property "Intersheetrefs" "${INTERSHEET_REFS}"
			(at 286.0583 51.9906 0)
			(effects
				(font
					(size 1.27 1.27)
				)
				(justify right)
				(hide yes)
			)
		)
	)
	(global_label "LED1"
		(shape input)
		(at 295.91 133.35 180)
		(fields_autoplaced yes)
		(effects
			(font
				(size 1.27 1.27)
			)
			(justify right)
		)
		(property "Intersheetrefs" "${INTERSHEET_REFS}"
			(at 288.8402 133.2706 0)
			(effects
				(font
					(size 1.27 1.27)
				)
				(justify right)
				(hide yes)
			)
		)
	)
	(global_label "TDI"
		(shape input)
		(at 95.25 146.05 0)
		(fields_autoplaced yes)
		(effects
			(font
				(size 1.27 1.27)
			)
			(justify left)
		)
		(property "Intersheetrefs" "${INTERSHEET_REFS}"
			(at 100.5055 145.9706 0)
			(effects
				(font
					(size 1.27 1.27)
				)
				(justify left)
				(hide yes)
			)
		)
	)
	(global_label "SCL"
		(shape input)
		(at 96.52 156.21 0)
		(fields_autoplaced yes)
		(effects
			(font
				(size 1.27 1.27)
			)
			(justify left)
		)
		(property "Intersheetrefs" "${INTERSHEET_REFS}"
			(at 102.4407 156.1306 0)
			(effects
				(font
					(size 1.27 1.27)
				)
				(justify left)
				(hide yes)
			)
		)
	)
	(global_label "AUDIO_MCLK"
		(shape input)
		(at 312.42 62.23 0)
		(fields_autoplaced yes)
		(effects
			(font
				(size 1.27 1.27)
			)
			(justify left)
		)
		(property "Intersheetrefs" "${INTERSHEET_REFS}"
			(at 326.4445 62.1506 0)
			(effects
				(font
					(size 1.27 1.27)
				)
				(justify left)
				(hide yes)
			)
		)
	)
	(global_label "TMS"
		(shape input)
		(at 95.25 140.97 0)
		(fields_autoplaced yes)
		(effects
			(font
				(size 1.27 1.27)
			)
			(justify left)
		)
		(property "Intersheetrefs" "${INTERSHEET_REFS}"
			(at 101.2917 140.8906 0)
			(effects
				(font
					(size 1.27 1.27)
				)
				(justify left)
				(hide yes)
			)
		)
	)
	(global_label "GPIO3"
		(shape input)
		(at 359.41 45.72 180)
		(fields_autoplaced yes)
		(effects
			(font
				(size 1.27 1.27)
			)
			(justify right)
		)
		(property "Intersheetrefs" "${INTERSHEET_REFS}"
			(at 351.3121 45.6406 0)
			(effects
				(font
					(size 1.27 1.27)
				)
				(justify right)
				(hide yes)
			)
		)
	)
	(global_label "SDA"
		(shape input)
		(at 218.44 133.35 180)
		(fields_autoplaced yes)
		(effects
			(font
				(size 1.27 1.27)
			)
			(justify right)
		)
		(property "Intersheetrefs" "${INTERSHEET_REFS}"
			(at 212.4588 133.2706 0)
			(effects
				(font
					(size 1.27 1.27)
				)
				(justify right)
				(hide yes)
			)
		)
	)
	(global_label "TCK"
		(shape input)
		(at 95.25 158.75 0)
		(fields_autoplaced yes)
		(effects
			(font
				(size 1.27 1.27)
			)
			(justify left)
		)
		(property "Intersheetrefs" "${INTERSHEET_REFS}"
			(at 101.1707 158.6706 0)
			(effects
				(font
					(size 1.27 1.27)
				)
				(justify left)
				(hide yes)
			)
		)
	)
	(global_label "DIP0"
		(shape input)
		(at 95.25 161.29 0)
		(fields_autoplaced yes)
		(effects
			(font
				(size 1.27 1.27)
			)
			(justify left)
		)
		(property "Intersheetrefs" "${INTERSHEET_REFS}"
			(at 102.0174 161.2106 0)
			(effects
				(font
					(size 1.27 1.27)
				)
				(justify left)
				(hide yes)
			)
		)
	)
	(global_label "USB_POWER_IN"
		(shape output)
		(at 344.17 201.93 0)
		(fields_autoplaced yes)
		(effects
			(font
				(size 1.27 1.27)
			)
			(justify left)
		)
		(property "Intersheetrefs" "${INTERSHEET_REFS}"
			(at 360.7345 201.8506 0)
			(effects
				(font
					(size 1.27 1.27)
				)
				(justify left)
				(hide yes)
			)
		)
	)
	(global_label "AUDIO_WCLK"
		(shape input)
		(at 312.42 54.61 0)
		(fields_autoplaced yes)
		(effects
			(font
				(size 1.27 1.27)
			)
			(justify left)
		)
		(property "Intersheetrefs" "${INTERSHEET_REFS}"
			(at 326.4445 54.5306 0)
			(effects
				(font
					(size 1.27 1.27)
				)
				(justify left)
				(hide yes)
			)
		)
	)
	(global_label "DIP1"
		(shape input)
		(at 365.76 143.51 180)
		(fields_autoplaced yes)
		(effects
			(font
				(size 1.27 1.27)
			)
			(justify right)
		)
		(property "Intersheetrefs" "${INTERSHEET_REFS}"
			(at 358.9926 143.4306 0)
			(effects
				(font
					(size 1.27 1.27)
				)
				(justify right)
				(hide yes)
			)
		)
	)
	(global_label "SDA"
		(shape input)
		(at 96.52 153.67 0)
		(fields_autoplaced yes)
		(effects
			(font
				(size 1.27 1.27)
			)
			(justify left)
		)
		(property "Intersheetrefs" "${INTERSHEET_REFS}"
			(at 102.5012 153.5906 0)
			(effects
				(font
					(size 1.27 1.27)
				)
				(justify left)
				(hide yes)
			)
		)
	)
	(global_label "LED0"
		(shape input)
		(at 295.91 128.27 180)
		(fields_autoplaced yes)
		(effects
			(font
				(size 1.27 1.27)
			)
			(justify right)
		)
		(property "Intersheetrefs" "${INTERSHEET_REFS}"
			(at 288.8402 128.1906 0)
			(effects
				(font
					(size 1.27 1.27)
				)
				(justify right)
				(hide yes)
			)
		)
	)
	(global_label "AUDIO_OUT_CH7_8"
		(shape input)
		(at 312.42 59.69 0)
		(fields_autoplaced yes)
		(effects
			(font
				(size 1.27 1.27)
			)
			(justify left)
		)
		(property "Intersheetrefs" "${INTERSHEET_REFS}"
			(at 332.0083 59.6106 0)
			(effects
				(font
					(size 1.27 1.27)
				)
				(justify left)
				(hide yes)
			)
		)
	)
	(global_label "40MHz_3V3"
		(shape input)
		(at 80.01 179.07 0)
		(fields_autoplaced yes)
		(effects
			(font
				(size 1.27 1.27)
			)
			(justify left)
		)
		(property "Intersheetrefs" "${INTERSHEET_REFS}"
			(at 93.1274 178.9906 0)
			(effects
				(font
					(size 1.27 1.27)
				)
				(justify left)
				(hide yes)
			)
		)
	)
	(global_label "GPIO2"
		(shape input)
		(at 359.41 43.18 180)
		(fields_autoplaced yes)
		(effects
			(font
				(size 1.27 1.27)
			)
			(justify right)
		)
		(property "Intersheetrefs" "${INTERSHEET_REFS}"
			(at 351.3121 43.1006 0)
			(effects
				(font
					(size 1.27 1.27)
				)
				(justify right)
				(hide yes)
			)
		)
	)
	(global_label "TXD"
		(shape input)
		(at 342.9 217.17 0)
		(fields_autoplaced yes)
		(effects
			(font
				(size 1.27 1.27)
			)
			(justify left)
		)
		(property "Intersheetrefs" "${INTERSHEET_REFS}"
			(at 348.7602 217.0906 0)
			(effects
				(font
					(size 1.27 1.27)
				)
				(justify left)
				(hide yes)
			)
		)
	)
	(symbol
		(lib_id "antmicroCapacitorsmisc:C_100n_0201")
		(at 111.76 90.17 90)
		(unit 1)
		(exclude_from_sim no)
		(in_bom yes)
		(on_board yes)
		(dnp no)
		(fields_autoplaced yes)
		(property "Reference" "C83"
			(at 114.3 86.3535 90)
			(effects
				(font
					(size 1.27 1.27)
					(thickness 0.15)
				)
				(justify right)
			)
		)
		(property "Value" "C_100n_0201"
			(at 121.92 69.85 0)
			(effects
				(font
					(size 1.27 1.27)
					(thickness 0.15)
				)
				(justify left bottom)
				(hide yes)
			)
		)
		(property "Footprint" "antmicro-footprints:C_0201"
			(at 124.46 69.85 0)
			(effects
				(font
					(size 1.27 1.27)
					(thickness 0.15)
				)
				(justify left bottom)
				(hide yes)
			)
		)
		(property "Datasheet" "https://www.yageo.com/en/Chart/Download/pdf/CC0201KRX6S5BB104"
			(at 127 69.85 0)
			(effects
				(font
					(size 1.27 1.27)
					(thickness 0.15)
				)
				(justify left bottom)
				(hide yes)
			)
		)
		(property "Description" "SMD Multilayer Ceramic Capacitor, 0.1 µF, 6.3 V, 0201 [0603 Metric], ± 10%, X6S, CC Series"
			(at 111.76 90.17 0)
			(effects
				(font
					(size 1.27 1.27)
				)
				(hide yes)
			)
		)
		(property "Manufacturer" "YAGEO"
			(at 132.08 69.85 0)
			(effects
				(font
					(size 1.27 1.27)
					(thickness 0.15)
				)
				(justify left bottom)
				(hide yes)
			)
		)
		(property "MPN" "CC0201KRX6S5BB104"
			(at 129.54 69.85 0)
			(effects
				(font
					(size 1.27 1.27)
					(thickness 0.15)
				)
				(justify left bottom)
				(hide yes)
			)
		)
		(property "Val" "100n"
			(at 114.3 88.8935 90)
			(effects
				(font
					(size 1.27 1.27)
					(thickness 0.15)
				)
				(justify right)
			)
		)
		(property "License" "Apache-2.0"
			(at 134.62 69.85 0)
			(effects
				(font
					(size 1.27 1.27)
					(thickness 0.15)
				)
				(justify left bottom)
				(hide yes)
			)
		)
		(property "Author" "Antmicro"
			(at 137.16 69.85 0)
			(effects
				(font
					(size 1.27 1.27)
					(thickness 0.15)
				)
				(justify left bottom)
				(hide yes)
			)
		)
		(property "Voltage" ""
			(at 139.7 69.85 0)
			(effects
				(font
					(size 1.27 1.27)
				)
				(justify left bottom)
				(hide yes)
			)
		)
		(property "Dielectric" ""
			(at 142.24 69.85 0)
			(effects
				(font
					(size 1.27 1.27)
				)
				(justify left bottom)
				(hide yes)
			)
		)
		(property "Public" "False"
			(at 144.78 69.85 0)
			(effects
				(font
					(size 1.27 1.27)
				)
				(justify left bottom)
				(hide yes)
			)
		)
		(pin "1"
		)
		(pin "2"
		)
		(instances
			(project "sdi-mipi-video-converter"
				(path ""
					(reference "C83")
					(unit 1)
				)
			)
		)
	)
	(symbol
		(lib_id "antmicropower:GND")
		(at 363.22 54.61 0)
		(unit 1)
		(exclude_from_sim no)
		(in_bom yes)
		(on_board yes)
		(dnp no)
		(fields_autoplaced yes)
		(property "Reference" "#PWR0263"
			(at 372.11 57.15 0)
			(effects
				(font
					(size 1.27 1.27)
					(thickness 0.15)
				)
				(justify left bottom)
				(hide yes)
			)
		)
		(property "Value" "GND"
			(at 363.22 59.69 0)
			(effects
				(font
					(size 1.27 1.27)
					(thickness 0.15)
				)
			)
		)
		(property "Footprint" ""
			(at 372.11 62.23 0)
			(effects
				(font
					(size 1.27 1.27)
					(thickness 0.15)
				)
				(justify left bottom)
				(hide yes)
			)
		)
		(property "Datasheet" ""
			(at 372.11 67.31 0)
			(effects
				(font
					(size 1.27 1.27)
					(thickness 0.15)
				)
				(justify left bottom)
				(hide yes)
			)
		)
		(property "Description" ""
			(at 363.22 54.61 0)
			(effects
				(font
					(size 1.27 1.27)
				)
				(hide yes)
			)
		)
		(property "Author" "Antmicro"
			(at 372.11 62.23 0)
			(effects
				(font
					(size 1.27 1.27)
					(thickness 0.15)
				)
				(justify left bottom)
				(hide yes)
			)
		)
		(property "License" "Apache-2.0"
			(at 372.11 64.77 0)
			(effects
				(font
					(size 1.27 1.27)
					(thickness 0.15)
				)
				(justify left bottom)
				(hide yes)
			)
		)
		(pin "1"
		)
		(instances
			(project "sdi-mipi-video-converter"
				(path ""
					(reference "#PWR0263")
					(unit 1)
				)
			)
		)
	)
	(symbol
		(lib_id "antmicropower:GND")
		(at 148.59 233.68 0)
		(unit 1)
		(exclude_from_sim no)
		(in_bom yes)
		(on_board yes)
		(dnp no)
		(fields_autoplaced yes)
		(property "Reference" "#PWR0249"
			(at 157.48 236.22 0)
			(effects
				(font
					(size 1.27 1.27)
					(thickness 0.15)
				)
				(justify left bottom)
				(hide yes)
			)
		)
		(property "Value" "GND"
			(at 148.59 238.76 0)
			(effects
				(font
					(size 1.27 1.27)
					(thickness 0.15)
				)
			)
		)
		(property "Footprint" ""
			(at 157.48 241.3 0)
			(effects
				(font
					(size 1.27 1.27)
					(thickness 0.15)
				)
				(justify left bottom)
				(hide yes)
			)
		)
		(property "Datasheet" ""
			(at 157.48 246.38 0)
			(effects
				(font
					(size 1.27 1.27)
					(thickness 0.15)
				)
				(justify left bottom)
				(hide yes)
			)
		)
		(property "Description" ""
			(at 148.59 233.68 0)
			(effects
				(font
					(size 1.27 1.27)
				)
				(hide yes)
			)
		)
		(property "Author" "Antmicro"
			(at 157.48 241.3 0)
			(effects
				(font
					(size 1.27 1.27)
					(thickness 0.15)
				)
				(justify left bottom)
				(hide yes)
			)
		)
		(property "License" "Apache-2.0"
			(at 157.48 243.84 0)
			(effects
				(font
					(size 1.27 1.27)
					(thickness 0.15)
				)
				(justify left bottom)
				(hide yes)
			)
		)
		(pin "1"
		)
		(instances
			(project "sdi-mipi-video-converter"
				(path ""
					(reference "#PWR0249")
					(unit 1)
				)
			)
		)
	)
	(symbol
		(lib_id "antmicropower:+3.3V")
		(at 114.3 121.92 0)
		(unit 1)
		(exclude_from_sim no)
		(in_bom yes)
		(on_board yes)
		(dnp no)
		(fields_autoplaced yes)
		(property "Reference" "#PWR0150"
			(at 114.3 125.73 0)
			(effects
				(font
					(size 1.27 1.27)
				)
				(hide yes)
			)
		)
		(property "Value" "+3V3"
			(at 114.3 116.84 0)
			(effects
				(font
					(size 1.27 1.27)
				)
			)
		)
		(property "Footprint" ""
			(at 114.3 121.92 0)
			(effects
				(font
					(size 1.27 1.27)
				)
				(hide yes)
			)
		)
		(property "Datasheet" ""
			(at 114.3 121.92 0)
			(effects
				(font
					(size 1.27 1.27)
				)
				(hide yes)
			)
		)
		(property "Description" ""
			(at 114.3 121.92 0)
			(effects
				(font
					(size 1.27 1.27)
				)
				(hide yes)
			)
		)
		(pin "1"
		)
		(instances
			(project "sdi-mipi-video-converter"
				(path ""
					(reference "#PWR0150")
					(unit 1)
				)
			)
		)
	)
	(symbol
		(lib_id "antmicroResistors0603:R_0R_0603")
		(at 351.79 52.07 0)
		(unit 1)
		(exclude_from_sim no)
		(in_bom yes)
		(on_board yes)
		(dnp no)
		(property "Reference" "R119"
			(at 354.33 54.61 0)
			(effects
				(font
					(size 1.27 1.27)
					(thickness 0.15)
				)
			)
		)
		(property "Value" "R_0R_0603"
			(at 372.11 64.77 0)
			(effects
				(font
					(size 1.27 1.27)
					(thickness 0.15)
				)
				(justify left bottom)
				(hide yes)
			)
		)
		(property "Footprint" "antmicro-footprints:R_0603_1608Metric"
			(at 372.11 67.31 0)
			(effects
				(font
					(size 1.27 1.27)
					(thickness 0.15)
				)
				(justify left bottom)
				(hide yes)
			)
		)
		(property "Datasheet" "https://www.bourns.com/docs/product-datasheets/cr.pdf?sfvrsn=574d41f6_14"
			(at 372.11 69.85 0)
			(effects
				(font
					(size 1.27 1.27)
					(thickness 0.15)
				)
				(justify left bottom)
				(hide yes)
			)
		)
		(property "Description" "Zero Ohm Resistor, Jumper, 0603 [1608 Metric], Thick Film, 100 mW, 1 A, Surface Mount Device, CR"
			(at 351.79 52.07 0)
			(effects
				(font
					(size 1.27 1.27)
				)
				(hide yes)
			)
		)
		(property "Manufacturer" "Bourns"
			(at 372.11 74.93 0)
			(effects
				(font
					(size 1.27 1.27)
					(thickness 0.15)
				)
				(justify left bottom)
				(hide yes)
			)
		)
		(property "MPN" "CR0603-J/-000ELF"
			(at 372.11 72.39 0)
			(effects
				(font
					(size 1.27 1.27)
					(thickness 0.15)
				)
				(justify left bottom)
				(hide yes)
			)
		)
		(property "Val" "0R"
			(at 354.33 56.515 0)
			(effects
				(font
					(size 1.27 1.27)
					(thickness 0.15)
				)
			)
		)
		(property "License" "Apache-2.0"
			(at 372.11 77.47 0)
			(effects
				(font
					(size 1.27 1.27)
					(thickness 0.15)
				)
				(justify left bottom)
				(hide yes)
			)
		)
		(property "Author" "Antmicro"
			(at 372.11 80.01 0)
			(effects
				(font
					(size 1.27 1.27)
					(thickness 0.15)
				)
				(justify left bottom)
				(hide yes)
			)
		)
		(property "Tolerance" "~"
			(at 372.11 62.23 0)
			(effects
				(font
					(size 1.27 1.27)
				)
				(justify left bottom)
				(hide yes)
			)
		)
		(property "Current" "1A"
			(at 372.11 82.55 0)
			(effects
				(font
					(size 1.27 1.27)
					(thickness 0.15)
				)
				(justify left bottom)
				(hide yes)
			)
		)
		(pin "1"
		)
		(pin "2"
		)
		(instances
			(project "sdi-mipi-video-converter"
				(path ""
					(reference "R119")
					(unit 1)
				)
			)
		)
	)
	(symbol
		(lib_id "antmicroResistors0402:R_0R_0402")
		(at 176.53 130.81 0)
		(unit 1)
		(exclude_from_sim no)
		(in_bom yes)
		(on_board yes)
		(dnp no)
		(property "Reference" "R122"
			(at 173.99 132.08 0)
			(effects
				(font
					(size 1.27 1.27)
					(thickness 0.15)
				)
			)
		)
		(property "Value" "R_0R_0402"
			(at 196.85 143.51 0)
			(effects
				(font
					(size 1.27 1.27)
					(thickness 0.15)
				)
				(justify left bottom)
				(hide yes)
			)
		)
		(property "Footprint" "antmicro-footprints:R_0402_1005Metric"
			(at 196.85 146.05 0)
			(effects
				(font
					(size 1.27 1.27)
					(thickness 0.15)
				)
				(justify left bottom)
				(hide yes)
			)
		)
		(property "Datasheet" "https://industrial.panasonic.com/cdbs/www-data/pdf/RDA0000/AOA0000C301.pdf"
			(at 196.85 148.59 0)
			(effects
				(font
					(size 1.27 1.27)
					(thickness 0.15)
				)
				(justify left bottom)
				(hide yes)
			)
		)
		(property "Description" "SMD Chip Resistor, Jumper, 0 ohm, 100 mW, 0402 [1005 Metric], Thick Film, General Purpose"
			(at 176.53 130.81 0)
			(effects
				(font
					(size 1.27 1.27)
				)
				(hide yes)
			)
		)
		(property "Manufacturer" "Panasonic"
			(at 196.85 153.67 0)
			(effects
				(font
					(size 1.27 1.27)
					(thickness 0.15)
				)
				(justify left bottom)
				(hide yes)
			)
		)
		(property "MPN" "ERJ2GE0R00X"
			(at 196.85 151.13 0)
			(effects
				(font
					(size 1.27 1.27)
					(thickness 0.15)
				)
				(justify left bottom)
				(hide yes)
			)
		)
		(property "Val" "0R"
			(at 182.88 132.08 0)
			(effects
				(font
					(size 1.27 1.27)
					(thickness 0.15)
				)
			)
		)
		(property "License" "Apache-2.0"
			(at 196.85 156.21 0)
			(effects
				(font
					(size 1.27 1.27)
					(thickness 0.15)
				)
				(justify left bottom)
				(hide yes)
			)
		)
		(property "Author" "Antmicro"
			(at 196.85 158.75 0)
			(effects
				(font
					(size 1.27 1.27)
					(thickness 0.15)
				)
				(justify left bottom)
				(hide yes)
			)
		)
		(property "Tolerance" "~"
			(at 196.85 140.97 0)
			(effects
				(font
					(size 1.27 1.27)
				)
				(justify left bottom)
				(hide yes)
			)
		)
		(property "Current" "1A"
			(at 196.85 161.29 0)
			(effects
				(font
					(size 1.27 1.27)
					(thickness 0.15)
				)
				(justify left bottom)
				(hide yes)
			)
		)
		(pin "1"
		)
		(pin "2"
		)
		(instances
			(project "sdi-mipi-video-converter"
				(path ""
					(reference "R122")
					(unit 1)
				)
			)
		)
	)
	(symbol
		(lib_id "antmicroFCCConnectors:Conn_FFC_WE_68715014522")
		(at 194.31 36.83 0)
		(unit 1)
		(exclude_from_sim no)
		(in_bom yes)
		(on_board yes)
		(dnp no)
		(property "Reference" "J4"
			(at 203.454 37.338 0)
			(effects
				(font
					(size 1.27 1.27)
					(thickness 0.15)
				)
				(justify left)
			)
		)
		(property "Value" "Conn_FFC_WE_68715014522_ONE-SIDE"
			(at 203.2 102.235 0)
			(effects
				(font
					(size 1.27 1.27)
					(thickness 0.15)
				)
				(justify left)
				(hide yes)
			)
		)
		(property "Footprint" "antmicro-footprints:Conn_FFC_WE_68715014x22"
			(at 213.36 46.99 0)
			(effects
				(font
					(size 1.27 1.27)
					(thickness 0.15)
				)
				(justify left bottom)
				(hide yes)
			)
		)
		(property "Datasheet" "https://www.we-online.com/components/products/datasheet/68715014522.pdf"
			(at 213.36 49.53 0)
			(effects
				(font
					(size 1.27 1.27)
					(thickness 0.15)
				)
				(justify left bottom)
				(hide yes)
			)
		)
		(property "Description" "FFC connector"
			(at 213.36 62.23 0)
			(effects
				(font
					(size 1.27 1.27)
				)
				(justify left bottom)
				(hide yes)
			)
		)
		(property "MPN" "68715014522"
			(at 203.454 39.878 0)
			(effects
				(font
					(size 1.27 1.27)
					(thickness 0.15)
				)
				(justify left)
			)
		)
		(property "Manufacturer" "Würth Elektronik"
			(at 213.36 54.61 0)
			(effects
				(font
					(size 1.27 1.27)
					(thickness 0.15)
				)
				(justify left bottom)
				(hide yes)
			)
		)
		(property "Author" "Antmicro"
			(at 213.36 57.15 0)
			(effects
				(font
					(size 1.27 1.27)
					(thickness 0.15)
				)
				(justify left bottom)
				(hide yes)
			)
		)
		(property "License" "Apache-2.0"
			(at 213.36 59.69 0)
			(effects
				(font
					(size 1.27 1.27)
					(thickness 0.15)
				)
				(justify left bottom)
				(hide yes)
			)
		)
		(pin "1"
		)
		(pin "10"
		)
		(pin "11"
		)
		(pin "12"
		)
		(pin "13"
		)
		(pin "14"
		)
		(pin "15"
		)
		(pin "16"
		)
		(pin "17"
		)
		(pin "18"
		)
		(pin "19"
		)
		(pin "2"
		)
		(pin "20"
		)
		(pin "21"
		)
		(pin "22"
		)
		(pin "23"
		)
		(pin "24"
		)
		(pin "25"
		)
		(pin "26"
		)
		(pin "27"
		)
		(pin "28"
		)
		(pin "29"
		)
		(pin "3"
		)
		(pin "30"
		)
		(pin "31"
		)
		(pin "32"
		)
		(pin "33"
		)
		(pin "34"
		)
		(pin "35"
		)
		(pin "36"
		)
		(pin "37"
		)
		(pin "38"
		)
		(pin "39"
		)
		(pin "4"
		)
		(pin "40"
		)
		(pin "41"
		)
		(pin "42"
		)
		(pin "43"
		)
		(pin "44"
		)
		(pin "45"
		)
		(pin "46"
		)
		(pin "47"
		)
		(pin "48"
		)
		(pin "49"
		)
		(pin "5"
		)
		(pin "50"
		)
		(pin "6"
		)
		(pin "7"
		)
		(pin "8"
		)
		(pin "9"
		)
		(pin "MP2"
		)
		(pin "MP1"
		)
		(instances
			(project "sdi-mipi-video-converter"
				(path ""
					(reference "J4")
					(unit 1)
				)
			)
		)
	)
	(symbol
		(lib_id "antmicroCapacitors0402:C_100n_0402")
		(at 148.59 265.43 90)
		(unit 1)
		(exclude_from_sim no)
		(in_bom yes)
		(on_board yes)
		(dnp no)
		(fields_autoplaced yes)
		(property "Reference" "C110"
			(at 151.13 261.6135 90)
			(effects
				(font
					(size 1.27 1.27)
					(thickness 0.15)
				)
				(justify right)
			)
		)
		(property "Value" "C_100n_0402"
			(at 158.75 245.11 0)
			(effects
				(font
					(size 1.27 1.27)
					(thickness 0.15)
				)
				(justify left bottom)
				(hide yes)
			)
		)
		(property "Footprint" "antmicro-footprints:C_0402_1005Metric"
			(at 161.29 245.11 0)
			(effects
				(font
					(size 1.27 1.27)
					(thickness 0.15)
				)
				(justify left bottom)
				(hide yes)
			)
		)
		(property "Datasheet" "https://www.murata.com/products/productdetail?partno=GRM155R61H104KE14%23"
			(at 163.83 245.11 0)
			(effects
				(font
					(size 1.27 1.27)
					(thickness 0.15)
				)
				(justify left bottom)
				(hide yes)
			)
		)
		(property "Description" "SMD Multilayer Ceramic Capacitor, 0.1 µF, 50 V, 0402 [1005 Metric], ± 10%, X5R, GRM Series"
			(at 148.59 265.43 0)
			(effects
				(font
					(size 1.27 1.27)
				)
				(hide yes)
			)
		)
		(property "Manufacturer" "Murata"
			(at 168.91 245.11 0)
			(effects
				(font
					(size 1.27 1.27)
					(thickness 0.15)
				)
				(justify left bottom)
				(hide yes)
			)
		)
		(property "MPN" "GRM155R61H104KE14D"
			(at 166.37 245.11 0)
			(effects
				(font
					(size 1.27 1.27)
					(thickness 0.15)
				)
				(justify left bottom)
				(hide yes)
			)
		)
		(property "Val" "100n"
			(at 151.13 264.1535 90)
			(effects
				(font
					(size 1.27 1.27)
					(thickness 0.15)
				)
				(justify right)
			)
		)
		(property "License" "Apache-2.0"
			(at 171.45 245.11 0)
			(effects
				(font
					(size 1.27 1.27)
					(thickness 0.15)
				)
				(justify left bottom)
				(hide yes)
			)
		)
		(property "Author" "Antmicro"
			(at 173.99 245.11 0)
			(effects
				(font
					(size 1.27 1.27)
					(thickness 0.15)
				)
				(justify left bottom)
				(hide yes)
			)
		)
		(property "Voltage" "50V"
			(at 176.53 245.11 0)
			(effects
				(font
					(size 1.27 1.27)
				)
				(justify left bottom)
				(hide yes)
			)
		)
		(property "Dielectric" "X5R"
			(at 179.07 245.11 0)
			(effects
				(font
					(size 1.27 1.27)
				)
				(justify left bottom)
				(hide yes)
			)
		)
		(pin "1"
		)
		(pin "2"
		)
		(instances
			(project "sdi-mipi-video-converter"
				(path ""
					(reference "C110")
					(unit 1)
				)
			)
		)
	)
	(symbol
		(lib_id "antmicroCapacitors0402:C_100n_0402")
		(at 53.34 238.76 270)
		(mirror x)
		(unit 1)
		(exclude_from_sim no)
		(in_bom yes)
		(on_board yes)
		(dnp no)
		(fields_autoplaced yes)
		(property "Reference" "C113"
			(at 50.8 234.9435 90)
			(effects
				(font
					(size 1.27 1.27)
					(thickness 0.15)
				)
				(justify right)
			)
		)
		(property "Value" "C_100n_0402"
			(at 43.18 218.44 0)
			(effects
				(font
					(size 1.27 1.27)
					(thickness 0.15)
				)
				(justify left bottom)
				(hide yes)
			)
		)
		(property "Footprint" "antmicro-footprints:C_0402_1005Metric"
			(at 40.64 218.44 0)
			(effects
				(font
					(size 1.27 1.27)
					(thickness 0.15)
				)
				(justify left bottom)
				(hide yes)
			)
		)
		(property "Datasheet" "https://www.murata.com/products/productdetail?partno=GRM155R61H104KE14%23"
			(at 38.1 218.44 0)
			(effects
				(font
					(size 1.27 1.27)
					(thickness 0.15)
				)
				(justify left bottom)
				(hide yes)
			)
		)
		(property "Description" "SMD Multilayer Ceramic Capacitor, 0.1 µF, 50 V, 0402 [1005 Metric], ± 10%, X5R, GRM Series"
			(at 53.34 238.76 0)
			(effects
				(font
					(size 1.27 1.27)
				)
				(hide yes)
			)
		)
		(property "Manufacturer" "Murata"
			(at 33.02 218.44 0)
			(effects
				(font
					(size 1.27 1.27)
					(thickness 0.15)
				)
				(justify left bottom)
				(hide yes)
			)
		)
		(property "MPN" "GRM155R61H104KE14D"
			(at 35.56 218.44 0)
			(effects
				(font
					(size 1.27 1.27)
					(thickness 0.15)
				)
				(justify left bottom)
				(hide yes)
			)
		)
		(property "Val" "100n"
			(at 50.8 237.4835 90)
			(effects
				(font
					(size 1.27 1.27)
					(thickness 0.15)
				)
				(justify right)
			)
		)
		(property "License" "Apache-2.0"
			(at 30.48 218.44 0)
			(effects
				(font
					(size 1.27 1.27)
					(thickness 0.15)
				)
				(justify left bottom)
				(hide yes)
			)
		)
		(property "Author" "Antmicro"
			(at 27.94 218.44 0)
			(effects
				(font
					(size 1.27 1.27)
					(thickness 0.15)
				)
				(justify left bottom)
				(hide yes)
			)
		)
		(property "Voltage" "50V"
			(at 25.4 218.44 0)
			(effects
				(font
					(size 1.27 1.27)
				)
				(justify left bottom)
				(hide yes)
			)
		)
		(property "Dielectric" "X5R"
			(at 22.86 218.44 0)
			(effects
				(font
					(size 1.27 1.27)
				)
				(justify left bottom)
				(hide yes)
			)
		)
		(pin "1"
		)
		(pin "2"
		)
		(instances
			(project "sdi-mipi-video-converter"
				(path ""
					(reference "C113")
					(unit 1)
				)
			)
		)
	)
	(symbol
		(lib_id "antmicroResistors0402:R_0R_0402")
		(at 226.06 133.35 0)
		(unit 1)
		(exclude_from_sim no)
		(in_bom yes)
		(on_board yes)
		(dnp no)
		(property "Reference" "R109"
			(at 223.52 134.62 0)
			(effects
				(font
					(size 1.27 1.27)
					(thickness 0.15)
				)
			)
		)
		(property "Value" "R_0R_0402"
			(at 246.38 146.05 0)
			(effects
				(font
					(size 1.27 1.27)
					(thickness 0.15)
				)
				(justify left bottom)
				(hide yes)
			)
		)
		(property "Footprint" "antmicro-footprints:R_0402_1005Metric"
			(at 246.38 148.59 0)
			(effects
				(font
					(size 1.27 1.27)
					(thickness 0.15)
				)
				(justify left bottom)
				(hide yes)
			)
		)
		(property "Datasheet" "https://industrial.panasonic.com/cdbs/www-data/pdf/RDA0000/AOA0000C301.pdf"
			(at 246.38 151.13 0)
			(effects
				(font
					(size 1.27 1.27)
					(thickness 0.15)
				)
				(justify left bottom)
				(hide yes)
			)
		)
		(property "Description" "SMD Chip Resistor, Jumper, 0 ohm, 100 mW, 0402 [1005 Metric], Thick Film, General Purpose"
			(at 226.06 133.35 0)
			(effects
				(font
					(size 1.27 1.27)
				)
				(hide yes)
			)
		)
		(property "Manufacturer" "Panasonic"
			(at 246.38 156.21 0)
			(effects
				(font
					(size 1.27 1.27)
					(thickness 0.15)
				)
				(justify left bottom)
				(hide yes)
			)
		)
		(property "MPN" "ERJ2GE0R00X"
			(at 246.38 153.67 0)
			(effects
				(font
					(size 1.27 1.27)
					(thickness 0.15)
				)
				(justify left bottom)
				(hide yes)
			)
		)
		(property "Val" "0R"
			(at 232.41 134.62 0)
			(effects
				(font
					(size 1.27 1.27)
					(thickness 0.15)
				)
			)
		)
		(property "License" "Apache-2.0"
			(at 246.38 158.75 0)
			(effects
				(font
					(size 1.27 1.27)
					(thickness 0.15)
				)
				(justify left bottom)
				(hide yes)
			)
		)
		(property "Author" "Antmicro"
			(at 246.38 161.29 0)
			(effects
				(font
					(size 1.27 1.27)
					(thickness 0.15)
				)
				(justify left bottom)
				(hide yes)
			)
		)
		(property "Tolerance" "~"
			(at 246.38 143.51 0)
			(effects
				(font
					(size 1.27 1.27)
				)
				(justify left bottom)
				(hide yes)
			)
		)
		(property "Current" "1A"
			(at 246.38 163.83 0)
			(effects
				(font
					(size 1.27 1.27)
					(thickness 0.15)
				)
				(justify left bottom)
				(hide yes)
			)
		)
		(pin "1"
		)
		(pin "2"
		)
		(instances
			(project "sdi-mipi-video-converter"
				(path ""
					(reference "R109")
					(unit 1)
				)
			)
		)
	)
	(symbol
		(lib_id "antmicroTestPoints:TP_0.75mm_SMD")
		(at 93.98 276.86 180)
		(unit 1)
		(exclude_from_sim no)
		(in_bom yes)
		(on_board yes)
		(dnp no)
		(fields_autoplaced yes)
		(property "Reference" "TP45"
			(at 90.805 273.05 0)
			(effects
				(font
					(size 1.27 1.27)
					(thickness 0.15)
				)
			)
		)
		(property "Value" "TP_0.75mm_SMD"
			(at 76.2 269.24 0)
			(effects
				(font
					(size 1.27 1.27)
					(thickness 0.15)
				)
				(justify left bottom)
				(hide yes)
			)
		)
		(property "Footprint" "antmicro-footprints:TP_SMD_0.75mm"
			(at 76.2 266.7 0)
			(effects
				(font
					(size 1.27 1.27)
					(thickness 0.15)
				)
				(justify left bottom)
				(hide yes)
			)
		)
		(property "Datasheet" ""
			(at 76.2 264.16 0)
			(effects
				(font
					(size 1.27 1.27)
					(thickness 0.15)
				)
				(justify left bottom)
				(hide yes)
			)
		)
		(property "Description" "SMT test point"
			(at 93.98 276.86 0)
			(effects
				(font
					(size 1.27 1.27)
				)
				(hide yes)
			)
		)
		(property "MPN" ""
			(at 76.2 261.62 0)
			(effects
				(font
					(size 1.27 1.27)
					(thickness 0.15)
				)
				(justify left bottom)
				(hide yes)
			)
		)
		(property "Manufacturer" ""
			(at 76.2 259.08 0)
			(effects
				(font
					(size 1.27 1.27)
					(thickness 0.15)
				)
				(justify left bottom)
				(hide yes)
			)
		)
		(property "Author" "Antmicro"
			(at 76.2 256.54 0)
			(effects
				(font
					(size 1.27 1.27)
					(thickness 0.15)
				)
				(justify left bottom)
				(hide yes)
			)
		)
		(property "License" "Apache-2.0"
			(at 76.2 254 0)
			(effects
				(font
					(size 1.27 1.27)
					(thickness 0.15)
				)
				(justify left bottom)
				(hide yes)
			)
		)
		(pin "1"
		)
		(instances
			(project "sdi-mipi-video-converter"
				(path ""
					(reference "TP45")
					(unit 1)
				)
			)
		)
	)
	(symbol
		(lib_id "antmicroResistors0603:R_200R_0603")
		(at 368.3 219.71 90)
		(unit 1)
		(exclude_from_sim no)
		(in_bom yes)
		(on_board yes)
		(dnp no)
		(fields_autoplaced yes)
		(property "Reference" "R135"
			(at 370.84 215.8999 90)
			(effects
				(font
					(size 1.27 1.27)
					(thickness 0.15)
				)
				(justify right)
			)
		)
		(property "Value" "R_200R_0603"
			(at 381 199.39 0)
			(effects
				(font
					(size 1.27 1.27)
					(thickness 0.15)
				)
				(justify left bottom)
				(hide yes)
			)
		)
		(property "Footprint" "antmicro-footprints:R_0603_1608Metric"
			(at 383.54 199.39 0)
			(effects
				(font
					(size 1.27 1.27)
					(thickness 0.15)
				)
				(justify left bottom)
				(hide yes)
			)
		)
		(property "Datasheet" "https://www.bourns.com/docs/product-datasheets/cr.pdf"
			(at 386.08 199.39 0)
			(effects
				(font
					(size 1.27 1.27)
					(thickness 0.15)
				)
				(justify left bottom)
				(hide yes)
			)
		)
		(property "Description" "SMD Chip Resistor, 200 ohm, ± 1%, 100 mW, 0603 [1608 Metric], Thick Film, General Purpose"
			(at 368.3 219.71 0)
			(effects
				(font
					(size 1.27 1.27)
				)
				(hide yes)
			)
		)
		(property "Manufacturer" "Bourns"
			(at 391.16 199.39 0)
			(effects
				(font
					(size 1.27 1.27)
					(thickness 0.15)
				)
				(justify left bottom)
				(hide yes)
			)
		)
		(property "MPN" "CR0603-FX-2000ELF"
			(at 388.62 199.39 0)
			(effects
				(font
					(size 1.27 1.27)
					(thickness 0.15)
				)
				(justify left bottom)
				(hide yes)
			)
		)
		(property "Val" "200R"
			(at 370.84 218.4399 90)
			(effects
				(font
					(size 1.27 1.27)
					(thickness 0.15)
				)
				(justify right)
			)
		)
		(property "License" "Apache-2.0"
			(at 393.7 199.39 0)
			(effects
				(font
					(size 1.27 1.27)
					(thickness 0.15)
				)
				(justify left bottom)
				(hide yes)
			)
		)
		(property "Author" "Antmicro"
			(at 396.24 199.39 0)
			(effects
				(font
					(size 1.27 1.27)
					(thickness 0.15)
				)
				(justify left bottom)
				(hide yes)
			)
		)
		(property "Tolerance" "1%"
			(at 378.46 199.39 0)
			(effects
				(font
					(size 1.27 1.27)
				)
				(justify left bottom)
				(hide yes)
			)
		)
		(pin "1"
		)
		(pin "2"
		)
		(instances
			(project "sdi-mipi-video-converter"
				(path ""
					(reference "R135")
					(unit 1)
				)
			)
		)
	)
	(symbol
		(lib_id "antmicroResistors0402:R_0R_0402")
		(at 176.53 140.97 0)
		(unit 1)
		(exclude_from_sim no)
		(in_bom yes)
		(on_board yes)
		(dnp no)
		(property "Reference" "R124"
			(at 173.99 142.24 0)
			(effects
				(font
					(size 1.27 1.27)
					(thickness 0.15)
				)
			)
		)
		(property "Value" "R_0R_0402"
			(at 196.85 153.67 0)
			(effects
				(font
					(size 1.27 1.27)
					(thickness 0.15)
				)
				(justify left bottom)
				(hide yes)
			)
		)
		(property "Footprint" "antmicro-footprints:R_0402_1005Metric"
			(at 196.85 156.21 0)
			(effects
				(font
					(size 1.27 1.27)
					(thickness 0.15)
				)
				(justify left bottom)
				(hide yes)
			)
		)
		(property "Datasheet" "https://industrial.panasonic.com/cdbs/www-data/pdf/RDA0000/AOA0000C301.pdf"
			(at 196.85 158.75 0)
			(effects
				(font
					(size 1.27 1.27)
					(thickness 0.15)
				)
				(justify left bottom)
				(hide yes)
			)
		)
		(property "Description" "SMD Chip Resistor, Jumper, 0 ohm, 100 mW, 0402 [1005 Metric], Thick Film, General Purpose"
			(at 176.53 140.97 0)
			(effects
				(font
					(size 1.27 1.27)
				)
				(hide yes)
			)
		)
		(property "Manufacturer" "Panasonic"
			(at 196.85 163.83 0)
			(effects
				(font
					(size 1.27 1.27)
					(thickness 0.15)
				)
				(justify left bottom)
				(hide yes)
			)
		)
		(property "MPN" "ERJ2GE0R00X"
			(at 196.85 161.29 0)
			(effects
				(font
					(size 1.27 1.27)
					(thickness 0.15)
				)
				(justify left bottom)
				(hide yes)
			)
		)
		(property "Val" "0R"
			(at 182.88 142.24 0)
			(effects
				(font
					(size 1.27 1.27)
					(thickness 0.15)
				)
			)
		)
		(property "License" "Apache-2.0"
			(at 196.85 166.37 0)
			(effects
				(font
					(size 1.27 1.27)
					(thickness 0.15)
				)
				(justify left bottom)
				(hide yes)
			)
		)
		(property "Author" "Antmicro"
			(at 196.85 168.91 0)
			(effects
				(font
					(size 1.27 1.27)
					(thickness 0.15)
				)
				(justify left bottom)
				(hide yes)
			)
		)
		(property "Tolerance" "~"
			(at 196.85 151.13 0)
			(effects
				(font
					(size 1.27 1.27)
				)
				(justify left bottom)
				(hide yes)
			)
		)
		(property "Current" "1A"
			(at 196.85 171.45 0)
			(effects
				(font
					(size 1.27 1.27)
					(thickness 0.15)
				)
				(justify left bottom)
				(hide yes)
			)
		)
		(pin "1"
		)
		(pin "2"
		)
		(instances
			(project "sdi-mipi-video-converter"
				(path ""
					(reference "R124")
					(unit 1)
				)
			)
		)
	)
	(symbol
		(lib_id "antmicroResistors0402:R_0R_0402")
		(at 176.53 123.19 0)
		(unit 1)
		(exclude_from_sim no)
		(in_bom yes)
		(on_board yes)
		(dnp no)
		(property "Reference" "R121"
			(at 174.625 124.46 0)
			(effects
				(font
					(size 1.27 1.27)
					(thickness 0.15)
				)
			)
		)
		(property "Value" "R_0R_0402"
			(at 196.85 135.89 0)
			(effects
				(font
					(size 1.27 1.27)
					(thickness 0.15)
				)
				(justify left bottom)
				(hide yes)
			)
		)
		(property "Footprint" "antmicro-footprints:R_0402_1005Metric"
			(at 196.85 138.43 0)
			(effects
				(font
					(size 1.27 1.27)
					(thickness 0.15)
				)
				(justify left bottom)
				(hide yes)
			)
		)
		(property "Datasheet" "https://industrial.panasonic.com/cdbs/www-data/pdf/RDA0000/AOA0000C301.pdf"
			(at 196.85 140.97 0)
			(effects
				(font
					(size 1.27 1.27)
					(thickness 0.15)
				)
				(justify left bottom)
				(hide yes)
			)
		)
		(property "Description" "SMD Chip Resistor, Jumper, 0 ohm, 100 mW, 0402 [1005 Metric], Thick Film, General Purpose"
			(at 176.53 123.19 0)
			(effects
				(font
					(size 1.27 1.27)
				)
				(hide yes)
			)
		)
		(property "Manufacturer" "Panasonic"
			(at 196.85 146.05 0)
			(effects
				(font
					(size 1.27 1.27)
					(thickness 0.15)
				)
				(justify left bottom)
				(hide yes)
			)
		)
		(property "MPN" "ERJ2GE0R00X"
			(at 196.85 143.51 0)
			(effects
				(font
					(size 1.27 1.27)
					(thickness 0.15)
				)
				(justify left bottom)
				(hide yes)
			)
		)
		(property "Val" "0R"
			(at 182.88 124.46 0)
			(effects
				(font
					(size 1.27 1.27)
					(thickness 0.15)
				)
			)
		)
		(property "License" "Apache-2.0"
			(at 196.85 148.59 0)
			(effects
				(font
					(size 1.27 1.27)
					(thickness 0.15)
				)
				(justify left bottom)
				(hide yes)
			)
		)
		(property "Author" "Antmicro"
			(at 196.85 151.13 0)
			(effects
				(font
					(size 1.27 1.27)
					(thickness 0.15)
				)
				(justify left bottom)
				(hide yes)
			)
		)
		(property "Tolerance" "~"
			(at 196.85 133.35 0)
			(effects
				(font
					(size 1.27 1.27)
				)
				(justify left bottom)
				(hide yes)
			)
		)
		(property "Current" "1A"
			(at 196.85 153.67 0)
			(effects
				(font
					(size 1.27 1.27)
					(thickness 0.15)
				)
				(justify left bottom)
				(hide yes)
			)
		)
		(pin "1"
		)
		(pin "2"
		)
		(instances
			(project "sdi-mipi-video-converter"
				(path ""
					(reference "R121")
					(unit 1)
				)
			)
		)
	)
	(symbol
		(lib_id "antmicroPMICPowerDistributionSwitchesLoadDrivers:DIO7553ST6")
		(at 85.09 229.87 0)
		(unit 1)
		(exclude_from_sim no)
		(in_bom yes)
		(on_board yes)
		(dnp no)
		(fields_autoplaced yes)
		(property "Reference" "U19"
			(at 93.98 222.25 0)
			(effects
				(font
					(size 1.27 1.27)
					(thickness 0.15)
				)
			)
		)
		(property "Value" "DIO7553ST6"
			(at 93.98 224.79 0)
			(effects
				(font
					(size 1.27 1.27)
					(thickness 0.15)
				)
			)
		)
		(property "Footprint" "antmicro-footprints:SOT-23-6"
			(at 116.84 237.49 0)
			(effects
				(font
					(size 1.27 1.27)
					(thickness 0.15)
				)
				(justify left bottom)
				(hide yes)
			)
		)
		(property "Datasheet" "https://www.mouser.com/datasheet/2/802/7e5c577022fb784effcb3cdb25b437c0-1815562.pdf"
			(at 116.84 240.03 0)
			(effects
				(font
					(size 1.27 1.27)
					(thickness 0.15)
				)
				(justify left bottom)
				(hide yes)
			)
		)
		(property "Description" "Power switch"
			(at 85.09 229.87 0)
			(effects
				(font
					(size 1.27 1.27)
				)
				(hide yes)
			)
		)
		(property "MPN" "DIO7553ST6"
			(at 116.84 242.57 0)
			(effects
				(font
					(size 1.27 1.27)
					(thickness 0.15)
				)
				(justify left bottom)
				(hide yes)
			)
		)
		(property "Manufacturer" "DIOO Microcircuits"
			(at 116.84 245.11 0)
			(effects
				(font
					(size 1.27 1.27)
					(thickness 0.15)
				)
				(justify left bottom)
				(hide yes)
			)
		)
		(property "Author" "Antmicro"
			(at 116.84 247.65 0)
			(effects
				(font
					(size 1.27 1.27)
					(thickness 0.15)
				)
				(justify left bottom)
				(hide yes)
			)
		)
		(property "License" "Apache-2.0"
			(at 116.84 250.19 0)
			(effects
				(font
					(size 1.27 1.27)
					(thickness 0.15)
				)
				(justify left bottom)
				(hide yes)
			)
		)
		(pin "1"
		)
		(pin "2"
		)
		(pin "3"
		)
		(pin "4"
		)
		(pin "5"
		)
		(pin "6"
		)
		(instances
			(project "sdi-mipi-video-converter"
				(path ""
					(reference "U19")
					(unit 1)
				)
			)
		)
	)
	(symbol
		(lib_id "antmicropower:GND")
		(at 168.91 275.59 0)
		(unit 1)
		(exclude_from_sim no)
		(in_bom yes)
		(on_board yes)
		(dnp no)
		(fields_autoplaced yes)
		(property "Reference" "#PWR0258"
			(at 177.8 278.13 0)
			(effects
				(font
					(size 1.27 1.27)
					(thickness 0.15)
				)
				(justify left bottom)
				(hide yes)
			)
		)
		(property "Value" "GND"
			(at 168.91 280.67 0)
			(effects
				(font
					(size 1.27 1.27)
					(thickness 0.15)
				)
			)
		)
		(property "Footprint" ""
			(at 177.8 283.21 0)
			(effects
				(font
					(size 1.27 1.27)
					(thickness 0.15)
				)
				(justify left bottom)
				(hide yes)
			)
		)
		(property "Datasheet" ""
			(at 177.8 288.29 0)
			(effects
				(font
					(size 1.27 1.27)
					(thickness 0.15)
				)
				(justify left bottom)
				(hide yes)
			)
		)
		(property "Description" ""
			(at 168.91 275.59 0)
			(effects
				(font
					(size 1.27 1.27)
				)
				(hide yes)
			)
		)
		(property "Author" "Antmicro"
			(at 177.8 283.21 0)
			(effects
				(font
					(size 1.27 1.27)
					(thickness 0.15)
				)
				(justify left bottom)
				(hide yes)
			)
		)
		(property "License" "Apache-2.0"
			(at 177.8 285.75 0)
			(effects
				(font
					(size 1.27 1.27)
					(thickness 0.15)
				)
				(justify left bottom)
				(hide yes)
			)
		)
		(pin "1"
		)
		(instances
			(project "sdi-mipi-video-converter"
				(path ""
					(reference "#PWR0258")
					(unit 1)
				)
			)
		)
	)
	(symbol
		(lib_id "antmicroResistors0603:R_15k_0603")
		(at 199.39 271.78 90)
		(unit 1)
		(exclude_from_sim no)
		(in_bom yes)
		(on_board yes)
		(dnp no)
		(fields_autoplaced yes)
		(property "Reference" "R108"
			(at 201.93 267.9699 90)
			(effects
				(font
					(size 1.27 1.27)
					(thickness 0.15)
				)
				(justify right)
			)
		)
		(property "Value" "R_15k_0603"
			(at 212.09 251.46 0)
			(effects
				(font
					(size 1.27 1.27)
					(thickness 0.15)
				)
				(justify left bottom)
				(hide yes)
			)
		)
		(property "Footprint" "antmicro-footprints:R_0603_1608Metric"
			(at 214.63 251.46 0)
			(effects
				(font
					(size 1.27 1.27)
					(thickness 0.15)
				)
				(justify left bottom)
				(hide yes)
			)
		)
		(property "Datasheet" "https://www.bourns.com/docs/product-datasheets/cr.pdf"
			(at 217.17 251.46 0)
			(effects
				(font
					(size 1.27 1.27)
					(thickness 0.15)
				)
				(justify left bottom)
				(hide yes)
			)
		)
		(property "Description" "SMD Chip Resistor, 15 kohm, ± 1%, 100 mW, 0603 [1608 Metric], Thick Film, General Purpose"
			(at 199.39 271.78 0)
			(effects
				(font
					(size 1.27 1.27)
				)
				(hide yes)
			)
		)
		(property "Manufacturer" "Bourns"
			(at 222.25 251.46 0)
			(effects
				(font
					(size 1.27 1.27)
					(thickness 0.15)
				)
				(justify left bottom)
				(hide yes)
			)
		)
		(property "MPN" "CR0603-FX-1502ELF"
			(at 219.71 251.46 0)
			(effects
				(font
					(size 1.27 1.27)
					(thickness 0.15)
				)
				(justify left bottom)
				(hide yes)
			)
		)
		(property "Val" "15k"
			(at 201.93 270.5099 90)
			(effects
				(font
					(size 1.27 1.27)
					(thickness 0.15)
				)
				(justify right)
			)
		)
		(property "License" "Apache-2.0"
			(at 224.79 251.46 0)
			(effects
				(font
					(size 1.27 1.27)
					(thickness 0.15)
				)
				(justify left bottom)
				(hide yes)
			)
		)
		(property "Author" "Antmicro"
			(at 227.33 251.46 0)
			(effects
				(font
					(size 1.27 1.27)
					(thickness 0.15)
				)
				(justify left bottom)
				(hide yes)
			)
		)
		(property "Tolerance" "1%"
			(at 209.55 251.46 0)
			(effects
				(font
					(size 1.27 1.27)
				)
				(justify left bottom)
				(hide yes)
			)
		)
		(pin "1"
		)
		(pin "2"
		)
		(instances
			(project "sdi-mipi-video-converter"
				(path ""
					(reference "R108")
					(unit 1)
				)
			)
		)
	)
	(symbol
		(lib_id "antmicropower:GND")
		(at 252.73 168.91 0)
		(unit 1)
		(exclude_from_sim no)
		(in_bom yes)
		(on_board yes)
		(dnp no)
		(fields_autoplaced yes)
		(property "Reference" "#PWR0156"
			(at 261.62 171.45 0)
			(effects
				(font
					(size 1.27 1.27)
					(thickness 0.15)
				)
				(justify left bottom)
				(hide yes)
			)
		)
		(property "Value" "GND"
			(at 252.73 173.99 0)
			(effects
				(font
					(size 1.27 1.27)
					(thickness 0.15)
				)
			)
		)
		(property "Footprint" ""
			(at 261.62 176.53 0)
			(effects
				(font
					(size 1.27 1.27)
					(thickness 0.15)
				)
				(justify left bottom)
				(hide yes)
			)
		)
		(property "Datasheet" ""
			(at 261.62 181.61 0)
			(effects
				(font
					(size 1.27 1.27)
					(thickness 0.15)
				)
				(justify left bottom)
				(hide yes)
			)
		)
		(property "Description" ""
			(at 252.73 168.91 0)
			(effects
				(font
					(size 1.27 1.27)
				)
				(hide yes)
			)
		)
		(property "Author" "Antmicro"
			(at 261.62 176.53 0)
			(effects
				(font
					(size 1.27 1.27)
					(thickness 0.15)
				)
				(justify left bottom)
				(hide yes)
			)
		)
		(property "License" "Apache-2.0"
			(at 261.62 179.07 0)
			(effects
				(font
					(size 1.27 1.27)
					(thickness 0.15)
				)
				(justify left bottom)
				(hide yes)
			)
		)
		(pin "1"
		)
		(instances
			(project "sdi-mipi-video-converter"
				(path ""
					(reference "#PWR0156")
					(unit 1)
				)
			)
		)
	)
	(symbol
		(lib_id "antmicropower:GND")
		(at 299.72 63.5 0)
		(unit 1)
		(exclude_from_sim no)
		(in_bom yes)
		(on_board yes)
		(dnp no)
		(fields_autoplaced yes)
		(property "Reference" "#PWR0155"
			(at 308.61 66.04 0)
			(effects
				(font
					(size 1.27 1.27)
					(thickness 0.15)
				)
				(justify left bottom)
				(hide yes)
			)
		)
		(property "Value" "GND"
			(at 299.72 68.58 0)
			(effects
				(font
					(size 1.27 1.27)
					(thickness 0.15)
				)
			)
		)
		(property "Footprint" ""
			(at 308.61 71.12 0)
			(effects
				(font
					(size 1.27 1.27)
					(thickness 0.15)
				)
				(justify left bottom)
				(hide yes)
			)
		)
		(property "Datasheet" ""
			(at 308.61 76.2 0)
			(effects
				(font
					(size 1.27 1.27)
					(thickness 0.15)
				)
				(justify left bottom)
				(hide yes)
			)
		)
		(property "Description" ""
			(at 299.72 63.5 0)
			(effects
				(font
					(size 1.27 1.27)
				)
				(hide yes)
			)
		)
		(property "Author" "Antmicro"
			(at 308.61 71.12 0)
			(effects
				(font
					(size 1.27 1.27)
					(thickness 0.15)
				)
				(justify left bottom)
				(hide yes)
			)
		)
		(property "License" "Apache-2.0"
			(at 308.61 73.66 0)
			(effects
				(font
					(size 1.27 1.27)
					(thickness 0.15)
				)
				(justify left bottom)
				(hide yes)
			)
		)
		(pin "1"
		)
		(instances
			(project "sdi-mipi-video-converter"
				(path ""
					(reference "#PWR0155")
					(unit 1)
				)
			)
		)
	)
	(symbol
		(lib_id "antmicroResistors0603:R_200R_0603")
		(at 383.54 219.71 90)
		(unit 1)
		(exclude_from_sim no)
		(in_bom yes)
		(on_board yes)
		(dnp no)
		(fields_autoplaced yes)
		(property "Reference" "R136"
			(at 386.08 215.8999 90)
			(effects
				(font
					(size 1.27 1.27)
					(thickness 0.15)
				)
				(justify right)
			)
		)
		(property "Value" "R_200R_0603"
			(at 396.24 199.39 0)
			(effects
				(font
					(size 1.27 1.27)
					(thickness 0.15)
				)
				(justify left bottom)
				(hide yes)
			)
		)
		(property "Footprint" "antmicro-footprints:R_0603_1608Metric"
			(at 398.78 199.39 0)
			(effects
				(font
					(size 1.27 1.27)
					(thickness 0.15)
				)
				(justify left bottom)
				(hide yes)
			)
		)
		(property "Datasheet" "https://www.bourns.com/docs/product-datasheets/cr.pdf"
			(at 401.32 199.39 0)
			(effects
				(font
					(size 1.27 1.27)
					(thickness 0.15)
				)
				(justify left bottom)
				(hide yes)
			)
		)
		(property "Description" "SMD Chip Resistor, 200 ohm, ± 1%, 100 mW, 0603 [1608 Metric], Thick Film, General Purpose"
			(at 383.54 219.71 0)
			(effects
				(font
					(size 1.27 1.27)
				)
				(hide yes)
			)
		)
		(property "Manufacturer" "Bourns"
			(at 406.4 199.39 0)
			(effects
				(font
					(size 1.27 1.27)
					(thickness 0.15)
				)
				(justify left bottom)
				(hide yes)
			)
		)
		(property "MPN" "CR0603-FX-2000ELF"
			(at 403.86 199.39 0)
			(effects
				(font
					(size 1.27 1.27)
					(thickness 0.15)
				)
				(justify left bottom)
				(hide yes)
			)
		)
		(property "Val" "200R"
			(at 386.08 218.4399 90)
			(effects
				(font
					(size 1.27 1.27)
					(thickness 0.15)
				)
				(justify right)
			)
		)
		(property "License" "Apache-2.0"
			(at 408.94 199.39 0)
			(effects
				(font
					(size 1.27 1.27)
					(thickness 0.15)
				)
				(justify left bottom)
				(hide yes)
			)
		)
		(property "Author" "Antmicro"
			(at 411.48 199.39 0)
			(effects
				(font
					(size 1.27 1.27)
					(thickness 0.15)
				)
				(justify left bottom)
				(hide yes)
			)
		)
		(property "Tolerance" "1%"
			(at 393.7 199.39 0)
			(effects
				(font
					(size 1.27 1.27)
				)
				(justify left bottom)
				(hide yes)
			)
		)
		(pin "1"
		)
		(pin "2"
		)
		(instances
			(project "sdi-mipi-video-converter"
				(path ""
					(reference "R136")
					(unit 1)
				)
			)
		)
	)
	(symbol
		(lib_id "antmicroLEDIndicationDiscrete:LED_G_0603_LTST-C190GKT")
		(at 158.75 173.99 270)
		(mirror x)
		(unit 1)
		(exclude_from_sim no)
		(in_bom yes)
		(on_board yes)
		(dnp no)
		(property "Reference" "D10"
			(at 162.56 171.4501 90)
			(effects
				(font
					(size 1.27 1.27)
					(thickness 0.15)
				)
				(justify left)
			)
		)
		(property "Value" "LED_G_0603_LTST-C190GKT"
			(at 155.702 186.182 0)
			(effects
				(font
					(size 1.27 1.27)
					(thickness 0.15)
				)
				(justify left)
			)
		)
		(property "Footprint" "antmicro-footprints:LED_0603_1608Metric_G"
			(at 148.59 151.13 0)
			(effects
				(font
					(size 1.27 1.27)
					(thickness 0.15)
				)
				(justify left bottom)
				(hide yes)
			)
		)
		(property "Datasheet" "https://media.digikey.com/pdf/Data%20Sheets/Lite-On%20PDFs/LTST-C190GKT.pdf"
			(at 146.05 151.13 0)
			(effects
				(font
					(size 1.27 1.27)
					(thickness 0.15)
				)
				(justify left bottom)
				(hide yes)
			)
		)
		(property "Description" "LED, Green, SMD, 0603, 20 mA, 2.1 V, 569 nm"
			(at 158.75 173.99 0)
			(effects
				(font
					(size 1.27 1.27)
				)
				(hide yes)
			)
		)
		(property "MPN" "LTST-C190GKT"
			(at 143.51 151.13 0)
			(effects
				(font
					(size 1.27 1.27)
					(thickness 0.15)
				)
				(justify left bottom)
				(hide yes)
			)
		)
		(property "Manufacturer" "Lite-On"
			(at 140.97 151.13 0)
			(effects
				(font
					(size 1.27 1.27)
					(thickness 0.15)
				)
				(justify left bottom)
				(hide yes)
			)
		)
		(property "Author" "Antmicro"
			(at 138.43 151.13 0)
			(effects
				(font
					(size 1.27 1.27)
					(thickness 0.15)
				)
				(justify left bottom)
				(hide yes)
			)
		)
		(property "License" "Apache-2.0"
			(at 135.89 151.13 0)
			(effects
				(font
					(size 1.27 1.27)
					(thickness 0.15)
				)
				(justify left bottom)
				(hide yes)
			)
		)
		(property "Color" "Green"
			(at 153.67 151.13 0)
			(effects
				(font
					(size 1.27 1.27)
				)
				(justify left bottom)
				(hide yes)
			)
		)
		(pin "1"
		)
		(pin "2"
		)
		(instances
			(project "sdi-mipi-video-converter"
				(path ""
					(reference "D10")
					(unit 1)
				)
			)
		)
	)
	(symbol
		(lib_id "antmicroCapacitors0402:C_47p_0402")
		(at 267.97 236.22 90)
		(unit 1)
		(exclude_from_sim no)
		(in_bom yes)
		(on_board yes)
		(dnp no)
		(fields_autoplaced yes)
		(property "Reference" "C117"
			(at 270.51 232.4035 90)
			(effects
				(font
					(size 1.27 1.27)
					(thickness 0.15)
				)
				(justify right)
			)
		)
		(property "Value" "C_47p_0402"
			(at 278.13 215.9 0)
			(effects
				(font
					(size 1.27 1.27)
					(thickness 0.15)
				)
				(justify left bottom)
				(hide yes)
			)
		)
		(property "Footprint" "antmicro-footprints:C_0402_1005Metric"
			(at 280.67 215.9 0)
			(effects
				(font
					(size 1.27 1.27)
					(thickness 0.15)
				)
				(justify left bottom)
				(hide yes)
			)
		)
		(property "Datasheet" "https://www.kemet.com/en/us/capacitors/product/C0402C470J5GACTU.html"
			(at 283.21 215.9 0)
			(effects
				(font
					(size 1.27 1.27)
					(thickness 0.15)
				)
				(justify left bottom)
				(hide yes)
			)
		)
		(property "Description" "SMD Multilayer Ceramic Capacitor, 47 pF, 50 V, 0402 [1005 Metric], ± 5%, C0G / NP0, C Series KEMET"
			(at 267.97 236.22 0)
			(effects
				(font
					(size 1.27 1.27)
				)
				(hide yes)
			)
		)
		(property "Manufacturer" "KEMET"
			(at 288.29 215.9 0)
			(effects
				(font
					(size 1.27 1.27)
					(thickness 0.15)
				)
				(justify left bottom)
				(hide yes)
			)
		)
		(property "MPN" "C0402C470J5GACTU"
			(at 285.75 215.9 0)
			(effects
				(font
					(size 1.27 1.27)
					(thickness 0.15)
				)
				(justify left bottom)
				(hide yes)
			)
		)
		(property "Val" "47p"
			(at 270.51 234.9435 90)
			(effects
				(font
					(size 1.27 1.27)
					(thickness 0.15)
				)
				(justify right)
			)
		)
		(property "License" "Apache-2.0"
			(at 290.83 215.9 0)
			(effects
				(font
					(size 1.27 1.27)
					(thickness 0.15)
				)
				(justify left bottom)
				(hide yes)
			)
		)
		(property "Author" "Antmicro"
			(at 293.37 215.9 0)
			(effects
				(font
					(size 1.27 1.27)
					(thickness 0.15)
				)
				(justify left bottom)
				(hide yes)
			)
		)
		(property "Voltage" ""
			(at 295.91 215.9 0)
			(effects
				(font
					(size 1.27 1.27)
				)
				(justify left bottom)
				(hide yes)
			)
		)
		(property "Dielectric" "C0G"
			(at 298.45 215.9 0)
			(effects
				(font
					(size 1.27 1.27)
				)
				(justify left bottom)
				(hide yes)
			)
		)
		(pin "1"
		)
		(pin "2"
		)
		(instances
			(project "sdi-mipi-video-converter"
				(path ""
					(reference "C117")
					(unit 1)
				)
			)
		)
	)
	(symbol
		(lib_id "antmicropower:GND")
		(at 308.61 242.57 0)
		(unit 1)
		(exclude_from_sim no)
		(in_bom yes)
		(on_board yes)
		(dnp no)
		(fields_autoplaced yes)
		(property "Reference" "#PWR0240"
			(at 317.5 245.11 0)
			(effects
				(font
					(size 1.27 1.27)
					(thickness 0.15)
				)
				(justify left bottom)
				(hide yes)
			)
		)
		(property "Value" "GND"
			(at 308.61 247.65 0)
			(effects
				(font
					(size 1.27 1.27)
					(thickness 0.15)
				)
			)
		)
		(property "Footprint" ""
			(at 317.5 250.19 0)
			(effects
				(font
					(size 1.27 1.27)
					(thickness 0.15)
				)
				(justify left bottom)
				(hide yes)
			)
		)
		(property "Datasheet" ""
			(at 317.5 255.27 0)
			(effects
				(font
					(size 1.27 1.27)
					(thickness 0.15)
				)
				(justify left bottom)
				(hide yes)
			)
		)
		(property "Description" ""
			(at 308.61 242.57 0)
			(effects
				(font
					(size 1.27 1.27)
				)
				(hide yes)
			)
		)
		(property "Author" "Antmicro"
			(at 317.5 250.19 0)
			(effects
				(font
					(size 1.27 1.27)
					(thickness 0.15)
				)
				(justify left bottom)
				(hide yes)
			)
		)
		(property "License" "Apache-2.0"
			(at 317.5 252.73 0)
			(effects
				(font
					(size 1.27 1.27)
					(thickness 0.15)
				)
				(justify left bottom)
				(hide yes)
			)
		)
		(pin "1"
		)
		(instances
			(project "sdi-mipi-video-converter"
				(path ""
					(reference "#PWR0240")
					(unit 1)
				)
			)
		)
	)
	(symbol
		(lib_id "antmicroResistors0603:R_0R_0603")
		(at 25.4 208.28 0)
		(unit 1)
		(exclude_from_sim no)
		(in_bom yes)
		(on_board yes)
		(dnp no)
		(property "Reference" "R117"
			(at 27.94 210.82 0)
			(effects
				(font
					(size 1.27 1.27)
					(thickness 0.15)
				)
			)
		)
		(property "Value" "R_0R_0603"
			(at 45.72 220.98 0)
			(effects
				(font
					(size 1.27 1.27)
					(thickness 0.15)
				)
				(justify left bottom)
				(hide yes)
			)
		)
		(property "Footprint" "antmicro-footprints:R_0603_1608Metric"
			(at 45.72 223.52 0)
			(effects
				(font
					(size 1.27 1.27)
					(thickness 0.15)
				)
				(justify left bottom)
				(hide yes)
			)
		)
		(property "Datasheet" "https://www.bourns.com/docs/product-datasheets/cr.pdf?sfvrsn=574d41f6_14"
			(at 45.72 226.06 0)
			(effects
				(font
					(size 1.27 1.27)
					(thickness 0.15)
				)
				(justify left bottom)
				(hide yes)
			)
		)
		(property "Description" "Zero Ohm Resistor, Jumper, 0603 [1608 Metric], Thick Film, 100 mW, 1 A, Surface Mount Device, CR"
			(at 25.4 208.28 0)
			(effects
				(font
					(size 1.27 1.27)
				)
				(hide yes)
			)
		)
		(property "Manufacturer" "Bourns"
			(at 45.72 231.14 0)
			(effects
				(font
					(size 1.27 1.27)
					(thickness 0.15)
				)
				(justify left bottom)
				(hide yes)
			)
		)
		(property "MPN" "CR0603-J/-000ELF"
			(at 45.72 228.6 0)
			(effects
				(font
					(size 1.27 1.27)
					(thickness 0.15)
				)
				(justify left bottom)
				(hide yes)
			)
		)
		(property "Val" "0R"
			(at 27.94 212.725 0)
			(effects
				(font
					(size 1.27 1.27)
					(thickness 0.15)
				)
			)
		)
		(property "License" "Apache-2.0"
			(at 45.72 233.68 0)
			(effects
				(font
					(size 1.27 1.27)
					(thickness 0.15)
				)
				(justify left bottom)
				(hide yes)
			)
		)
		(property "Author" "Antmicro"
			(at 45.72 236.22 0)
			(effects
				(font
					(size 1.27 1.27)
					(thickness 0.15)
				)
				(justify left bottom)
				(hide yes)
			)
		)
		(property "Tolerance" "~"
			(at 45.72 218.44 0)
			(effects
				(font
					(size 1.27 1.27)
				)
				(justify left bottom)
				(hide yes)
			)
		)
		(property "Current" "1A"
			(at 45.72 238.76 0)
			(effects
				(font
					(size 1.27 1.27)
					(thickness 0.15)
				)
				(justify left bottom)
				(hide yes)
			)
		)
		(pin "1"
		)
		(pin "2"
		)
		(instances
			(project "sdi-mipi-video-converter"
				(path ""
					(reference "R117")
					(unit 1)
				)
			)
		)
	)
	(symbol
		(lib_id "antmicropower:GND")
		(at 72.39 248.92 0)
		(unit 1)
		(exclude_from_sim no)
		(in_bom yes)
		(on_board yes)
		(dnp no)
		(fields_autoplaced yes)
		(property "Reference" "#PWR010"
			(at 81.28 251.46 0)
			(effects
				(font
					(size 1.27 1.27)
					(thickness 0.15)
				)
				(justify left bottom)
				(hide yes)
			)
		)
		(property "Value" "GND"
			(at 72.39 254 0)
			(effects
				(font
					(size 1.27 1.27)
					(thickness 0.15)
				)
			)
		)
		(property "Footprint" ""
			(at 81.28 256.54 0)
			(effects
				(font
					(size 1.27 1.27)
					(thickness 0.15)
				)
				(justify left bottom)
				(hide yes)
			)
		)
		(property "Datasheet" ""
			(at 81.28 261.62 0)
			(effects
				(font
					(size 1.27 1.27)
					(thickness 0.15)
				)
				(justify left bottom)
				(hide yes)
			)
		)
		(property "Description" ""
			(at 72.39 248.92 0)
			(effects
				(font
					(size 1.27 1.27)
				)
				(hide yes)
			)
		)
		(property "Author" "Antmicro"
			(at 81.28 256.54 0)
			(effects
				(font
					(size 1.27 1.27)
					(thickness 0.15)
				)
				(justify left bottom)
				(hide yes)
			)
		)
		(property "License" "Apache-2.0"
			(at 81.28 259.08 0)
			(effects
				(font
					(size 1.27 1.27)
					(thickness 0.15)
				)
				(justify left bottom)
				(hide yes)
			)
		)
		(pin "1"
		)
		(instances
			(project "sdi-mipi-video-converter"
				(path ""
					(reference "#PWR010")
					(unit 1)
				)
			)
		)
	)
	(symbol
		(lib_id "antmicropower:GND")
		(at 170.18 176.53 0)
		(unit 1)
		(exclude_from_sim no)
		(in_bom yes)
		(on_board yes)
		(dnp no)
		(fields_autoplaced yes)
		(property "Reference" "#PWR0252"
			(at 179.07 179.07 0)
			(effects
				(font
					(size 1.27 1.27)
					(thickness 0.15)
				)
				(justify left bottom)
				(hide yes)
			)
		)
		(property "Value" "GND"
			(at 170.18 181.61 0)
			(effects
				(font
					(size 1.27 1.27)
					(thickness 0.15)
				)
			)
		)
		(property "Footprint" ""
			(at 179.07 184.15 0)
			(effects
				(font
					(size 1.27 1.27)
					(thickness 0.15)
				)
				(justify left bottom)
				(hide yes)
			)
		)
		(property "Datasheet" ""
			(at 179.07 189.23 0)
			(effects
				(font
					(size 1.27 1.27)
					(thickness 0.15)
				)
				(justify left bottom)
				(hide yes)
			)
		)
		(property "Description" ""
			(at 170.18 176.53 0)
			(effects
				(font
					(size 1.27 1.27)
				)
				(hide yes)
			)
		)
		(property "Author" "Antmicro"
			(at 179.07 184.15 0)
			(effects
				(font
					(size 1.27 1.27)
					(thickness 0.15)
				)
				(justify left bottom)
				(hide yes)
			)
		)
		(property "License" "Apache-2.0"
			(at 179.07 186.69 0)
			(effects
				(font
					(size 1.27 1.27)
					(thickness 0.15)
				)
				(justify left bottom)
				(hide yes)
			)
		)
		(pin "1"
		)
		(instances
			(project "sdi-mipi-video-converter"
				(path ""
					(reference "#PWR0252")
					(unit 1)
				)
			)
		)
	)
	(symbol
		(lib_id "antmicroUSBConnectors:USB-C_GCT_USB4105-GF-A")
		(at 262.89 213.36 0)
		(unit 1)
		(exclude_from_sim no)
		(in_bom yes)
		(on_board yes)
		(dnp no)
		(fields_autoplaced yes)
		(property "Reference" "J1"
			(at 249.555 205.74 0)
			(effects
				(font
					(size 1.27 1.27)
					(thickness 0.15)
				)
			)
		)
		(property "Value" "USB-C_USB4105-GF-A"
			(at 249.555 208.28 0)
			(effects
				(font
					(size 1.27 1.27)
					(thickness 0.15)
				)
			)
		)
		(property "Footprint" "antmicro-footprints:USB-C_Receptacle_GCT_USB4105-GF-A"
			(at 300.99 220.98 0)
			(effects
				(font
					(size 1.27 1.27)
					(thickness 0.15)
				)
				(justify left bottom)
				(hide yes)
			)
		)
		(property "Datasheet" "https://gct.co/files/drawings/usb4105.pdf"
			(at 300.99 223.52 0)
			(effects
				(font
					(size 1.27 1.27)
					(thickness 0.15)
				)
				(justify left bottom)
				(hide yes)
			)
		)
		(property "Description" "USB-C (USB TYPE-C) USB 2.0 Receptacle Connector 24 (16+8 Dummy) Position Surface Mount, Right Angle"
			(at 262.89 213.36 0)
			(effects
				(font
					(size 1.27 1.27)
				)
				(hide yes)
			)
		)
		(property "Manufacturer" "GCT"
			(at 300.99 226.06 0)
			(effects
				(font
					(size 1.27 1.27)
					(thickness 0.15)
				)
				(justify left bottom)
				(hide yes)
			)
		)
		(property "MPN" "USB4105-GF-A"
			(at 300.99 228.6 0)
			(effects
				(font
					(size 1.27 1.27)
					(thickness 0.15)
				)
				(justify left bottom)
				(hide yes)
			)
		)
		(property "Author" "Antmicro"
			(at 300.99 231.14 0)
			(effects
				(font
					(size 1.27 1.27)
					(thickness 0.15)
				)
				(justify left bottom)
				(hide yes)
			)
		)
		(property "License" "Apache-2.0"
			(at 300.99 233.68 0)
			(effects
				(font
					(size 1.27 1.27)
					(thickness 0.15)
				)
				(justify left bottom)
				(hide yes)
			)
		)
		(pin "A1"
		)
		(pin "A12"
		)
		(pin "A4"
		)
		(pin "A5"
		)
		(pin "A6"
		)
		(pin "A7"
		)
		(pin "A8"
		)
		(pin "A9"
		)
		(pin "B1"
		)
		(pin "B12"
		)
		(pin "B4"
		)
		(pin "B5"
		)
		(pin "B6"
		)
		(pin "B7"
		)
		(pin "B8"
		)
		(pin "B9"
		)
		(pin "SH"
		)
		(instances
			(project "sdi-mipi-video-converter"
				(path ""
					(reference "J1")
					(unit 1)
				)
			)
		)
	)
	(symbol
		(lib_id "antmicroResistors0402:R_0R_0402")
		(at 176.53 118.11 0)
		(unit 1)
		(exclude_from_sim no)
		(in_bom yes)
		(on_board yes)
		(dnp no)
		(property "Reference" "R74"
			(at 174.625 119.38 0)
			(effects
				(font
					(size 1.27 1.27)
					(thickness 0.15)
				)
			)
		)
		(property "Value" "R_0R_0402"
			(at 196.85 130.81 0)
			(effects
				(font
					(size 1.27 1.27)
					(thickness 0.15)
				)
				(justify left bottom)
				(hide yes)
			)
		)
		(property "Footprint" "antmicro-footprints:R_0402_1005Metric"
			(at 196.85 133.35 0)
			(effects
				(font
					(size 1.27 1.27)
					(thickness 0.15)
				)
				(justify left bottom)
				(hide yes)
			)
		)
		(property "Datasheet" "https://industrial.panasonic.com/cdbs/www-data/pdf/RDA0000/AOA0000C301.pdf"
			(at 196.85 135.89 0)
			(effects
				(font
					(size 1.27 1.27)
					(thickness 0.15)
				)
				(justify left bottom)
				(hide yes)
			)
		)
		(property "Description" "SMD Chip Resistor, Jumper, 0 ohm, 100 mW, 0402 [1005 Metric], Thick Film, General Purpose"
			(at 176.53 118.11 0)
			(effects
				(font
					(size 1.27 1.27)
				)
				(hide yes)
			)
		)
		(property "Manufacturer" "Panasonic"
			(at 196.85 140.97 0)
			(effects
				(font
					(size 1.27 1.27)
					(thickness 0.15)
				)
				(justify left bottom)
				(hide yes)
			)
		)
		(property "MPN" "ERJ2GE0R00X"
			(at 196.85 138.43 0)
			(effects
				(font
					(size 1.27 1.27)
					(thickness 0.15)
				)
				(justify left bottom)
				(hide yes)
			)
		)
		(property "Val" "0R"
			(at 182.88 119.38 0)
			(effects
				(font
					(size 1.27 1.27)
					(thickness 0.15)
				)
			)
		)
		(property "License" "Apache-2.0"
			(at 196.85 143.51 0)
			(effects
				(font
					(size 1.27 1.27)
					(thickness 0.15)
				)
				(justify left bottom)
				(hide yes)
			)
		)
		(property "Author" "Antmicro"
			(at 196.85 146.05 0)
			(effects
				(font
					(size 1.27 1.27)
					(thickness 0.15)
				)
				(justify left bottom)
				(hide yes)
			)
		)
		(property "Tolerance" "~"
			(at 196.85 128.27 0)
			(effects
				(font
					(size 1.27 1.27)
				)
				(justify left bottom)
				(hide yes)
			)
		)
		(property "Current" "1A"
			(at 196.85 148.59 0)
			(effects
				(font
					(size 1.27 1.27)
					(thickness 0.15)
				)
				(justify left bottom)
				(hide yes)
			)
		)
		(pin "1"
		)
		(pin "2"
		)
		(instances
			(project "sdi-mipi-video-converter"
				(path ""
					(reference "R74")
					(unit 1)
				)
			)
		)
	)
	(symbol
		(lib_id "antmicroResistors0402:R_0R_0402")
		(at 236.22 113.03 0)
		(unit 1)
		(exclude_from_sim no)
		(in_bom yes)
		(on_board yes)
		(dnp no)
		(property "Reference" "R128"
			(at 233.68 114.3 0)
			(effects
				(font
					(size 1.27 1.27)
					(thickness 0.15)
				)
			)
		)
		(property "Value" "R_0R_0402"
			(at 256.54 125.73 0)
			(effects
				(font
					(size 1.27 1.27)
					(thickness 0.15)
				)
				(justify left bottom)
				(hide yes)
			)
		)
		(property "Footprint" "antmicro-footprints:R_0402_1005Metric"
			(at 256.54 128.27 0)
			(effects
				(font
					(size 1.27 1.27)
					(thickness 0.15)
				)
				(justify left bottom)
				(hide yes)
			)
		)
		(property "Datasheet" "https://industrial.panasonic.com/cdbs/www-data/pdf/RDA0000/AOA0000C301.pdf"
			(at 256.54 130.81 0)
			(effects
				(font
					(size 1.27 1.27)
					(thickness 0.15)
				)
				(justify left bottom)
				(hide yes)
			)
		)
		(property "Description" "SMD Chip Resistor, Jumper, 0 ohm, 100 mW, 0402 [1005 Metric], Thick Film, General Purpose"
			(at 236.22 113.03 0)
			(effects
				(font
					(size 1.27 1.27)
				)
				(hide yes)
			)
		)
		(property "Manufacturer" "Panasonic"
			(at 256.54 135.89 0)
			(effects
				(font
					(size 1.27 1.27)
					(thickness 0.15)
				)
				(justify left bottom)
				(hide yes)
			)
		)
		(property "MPN" "ERJ2GE0R00X"
			(at 256.54 133.35 0)
			(effects
				(font
					(size 1.27 1.27)
					(thickness 0.15)
				)
				(justify left bottom)
				(hide yes)
			)
		)
		(property "Val" "0R"
			(at 242.57 114.3 0)
			(effects
				(font
					(size 1.27 1.27)
					(thickness 0.15)
				)
			)
		)
		(property "License" "Apache-2.0"
			(at 256.54 138.43 0)
			(effects
				(font
					(size 1.27 1.27)
					(thickness 0.15)
				)
				(justify left bottom)
				(hide yes)
			)
		)
		(property "Author" "Antmicro"
			(at 256.54 140.97 0)
			(effects
				(font
					(size 1.27 1.27)
					(thickness 0.15)
				)
				(justify left bottom)
				(hide yes)
			)
		)
		(property "Tolerance" "~"
			(at 256.54 123.19 0)
			(effects
				(font
					(size 1.27 1.27)
				)
				(justify left bottom)
				(hide yes)
			)
		)
		(property "Current" "1A"
			(at 256.54 143.51 0)
			(effects
				(font
					(size 1.27 1.27)
					(thickness 0.15)
				)
				(justify left bottom)
				(hide yes)
			)
		)
		(pin "1"
		)
		(pin "2"
		)
		(instances
			(project "sdi-mipi-video-converter"
				(path ""
					(reference "R128")
					(unit 1)
				)
			)
		)
	)
	(symbol
		(lib_id "antmicroFCCConnectors:Conn_FFC_WE_68715014522")
		(at 255.27 36.83 0)
		(unit 1)
		(exclude_from_sim no)
		(in_bom yes)
		(on_board yes)
		(dnp no)
		(property "Reference" "J6"
			(at 264.414 37.338 0)
			(effects
				(font
					(size 1.27 1.27)
					(thickness 0.15)
				)
				(justify left)
			)
		)
		(property "Value" "Conn_FFC_WE_68715014522_ONE-SIDE"
			(at 264.16 102.235 0)
			(effects
				(font
					(size 1.27 1.27)
					(thickness 0.15)
				)
				(justify left)
				(hide yes)
			)
		)
		(property "Footprint" "antmicro-footprints:Conn_FFC_WE_68715014x22"
			(at 274.32 46.99 0)
			(effects
				(font
					(size 1.27 1.27)
					(thickness 0.15)
				)
				(justify left bottom)
				(hide yes)
			)
		)
		(property "Datasheet" "https://www.we-online.com/components/products/datasheet/68715014522.pdf"
			(at 274.32 49.53 0)
			(effects
				(font
					(size 1.27 1.27)
					(thickness 0.15)
				)
				(justify left bottom)
				(hide yes)
			)
		)
		(property "Description" "FFC connector"
			(at 274.32 62.23 0)
			(effects
				(font
					(size 1.27 1.27)
				)
				(justify left bottom)
				(hide yes)
			)
		)
		(property "MPN" "68715014522"
			(at 264.414 39.878 0)
			(effects
				(font
					(size 1.27 1.27)
					(thickness 0.15)
				)
				(justify left)
			)
		)
		(property "Manufacturer" "Würth Elektronik"
			(at 274.32 54.61 0)
			(effects
				(font
					(size 1.27 1.27)
					(thickness 0.15)
				)
				(justify left bottom)
				(hide yes)
			)
		)
		(property "Author" "Antmicro"
			(at 274.32 57.15 0)
			(effects
				(font
					(size 1.27 1.27)
					(thickness 0.15)
				)
				(justify left bottom)
				(hide yes)
			)
		)
		(property "License" "Apache-2.0"
			(at 274.32 59.69 0)
			(effects
				(font
					(size 1.27 1.27)
					(thickness 0.15)
				)
				(justify left bottom)
				(hide yes)
			)
		)
		(pin "1"
		)
		(pin "10"
		)
		(pin "11"
		)
		(pin "12"
		)
		(pin "13"
		)
		(pin "14"
		)
		(pin "15"
		)
		(pin "16"
		)
		(pin "17"
		)
		(pin "18"
		)
		(pin "19"
		)
		(pin "2"
		)
		(pin "20"
		)
		(pin "21"
		)
		(pin "22"
		)
		(pin "23"
		)
		(pin "24"
		)
		(pin "25"
		)
		(pin "26"
		)
		(pin "27"
		)
		(pin "28"
		)
		(pin "29"
		)
		(pin "3"
		)
		(pin "30"
		)
		(pin "31"
		)
		(pin "32"
		)
		(pin "33"
		)
		(pin "34"
		)
		(pin "35"
		)
		(pin "36"
		)
		(pin "37"
		)
		(pin "38"
		)
		(pin "39"
		)
		(pin "4"
		)
		(pin "40"
		)
		(pin "41"
		)
		(pin "42"
		)
		(pin "43"
		)
		(pin "44"
		)
		(pin "45"
		)
		(pin "46"
		)
		(pin "47"
		)
		(pin "48"
		)
		(pin "49"
		)
		(pin "5"
		)
		(pin "50"
		)
		(pin "6"
		)
		(pin "7"
		)
		(pin "8"
		)
		(pin "9"
		)
		(pin "MP2"
		)
		(pin "MP1"
		)
		(instances
			(project "sdi-mipi-video-converter"
				(path ""
					(reference "J6")
					(unit 1)
				)
			)
		)
	)
	(symbol
		(lib_id "antmicropower:GND")
		(at 199.39 274.32 0)
		(unit 1)
		(exclude_from_sim no)
		(in_bom yes)
		(on_board yes)
		(dnp no)
		(fields_autoplaced yes)
		(property "Reference" "#PWR0256"
			(at 208.28 276.86 0)
			(effects
				(font
					(size 1.27 1.27)
					(thickness 0.15)
				)
				(justify left bottom)
				(hide yes)
			)
		)
		(property "Value" "GND"
			(at 199.39 279.4 0)
			(effects
				(font
					(size 1.27 1.27)
					(thickness 0.15)
				)
			)
		)
		(property "Footprint" ""
			(at 208.28 281.94 0)
			(effects
				(font
					(size 1.27 1.27)
					(thickness 0.15)
				)
				(justify left bottom)
				(hide yes)
			)
		)
		(property "Datasheet" ""
			(at 208.28 287.02 0)
			(effects
				(font
					(size 1.27 1.27)
					(thickness 0.15)
				)
				(justify left bottom)
				(hide yes)
			)
		)
		(property "Description" ""
			(at 199.39 274.32 0)
			(effects
				(font
					(size 1.27 1.27)
				)
				(hide yes)
			)
		)
		(property "Author" "Antmicro"
			(at 208.28 281.94 0)
			(effects
				(font
					(size 1.27 1.27)
					(thickness 0.15)
				)
				(justify left bottom)
				(hide yes)
			)
		)
		(property "License" "Apache-2.0"
			(at 208.28 284.48 0)
			(effects
				(font
					(size 1.27 1.27)
					(thickness 0.15)
				)
				(justify left bottom)
				(hide yes)
			)
		)
		(pin "1"
		)
		(instances
			(project "sdi-mipi-video-converter"
				(path ""
					(reference "#PWR0256")
					(unit 1)
				)
			)
		)
	)
	(symbol
		(lib_id "antmicropower:GND")
		(at 111.76 91.44 0)
		(unit 1)
		(exclude_from_sim no)
		(in_bom yes)
		(on_board yes)
		(dnp no)
		(fields_autoplaced yes)
		(property "Reference" "#PWR0149"
			(at 120.65 93.98 0)
			(effects
				(font
					(size 1.27 1.27)
					(thickness 0.15)
				)
				(justify left bottom)
				(hide yes)
			)
		)
		(property "Value" "GND"
			(at 111.76 96.52 0)
			(effects
				(font
					(size 1.27 1.27)
					(thickness 0.15)
				)
			)
		)
		(property "Footprint" ""
			(at 120.65 99.06 0)
			(effects
				(font
					(size 1.27 1.27)
					(thickness 0.15)
				)
				(justify left bottom)
				(hide yes)
			)
		)
		(property "Datasheet" ""
			(at 120.65 104.14 0)
			(effects
				(font
					(size 1.27 1.27)
					(thickness 0.15)
				)
				(justify left bottom)
				(hide yes)
			)
		)
		(property "Description" ""
			(at 111.76 91.44 0)
			(effects
				(font
					(size 1.27 1.27)
				)
				(hide yes)
			)
		)
		(property "Author" "Antmicro"
			(at 120.65 99.06 0)
			(effects
				(font
					(size 1.27 1.27)
					(thickness 0.15)
				)
				(justify left bottom)
				(hide yes)
			)
		)
		(property "License" "Apache-2.0"
			(at 120.65 101.6 0)
			(effects
				(font
					(size 1.27 1.27)
					(thickness 0.15)
				)
				(justify left bottom)
				(hide yes)
			)
		)
		(pin "1"
		)
		(instances
			(project "sdi-mipi-video-converter"
				(path ""
					(reference "#PWR0149")
					(unit 1)
				)
			)
		)
	)
	(symbol
		(lib_id "antmicroResistors0402:R_0R_0402")
		(at 236.22 118.11 0)
		(unit 1)
		(exclude_from_sim no)
		(in_bom yes)
		(on_board yes)
		(dnp no)
		(property "Reference" "R129"
			(at 233.68 119.38 0)
			(effects
				(font
					(size 1.27 1.27)
					(thickness 0.15)
				)
			)
		)
		(property "Value" "R_0R_0402"
			(at 256.54 130.81 0)
			(effects
				(font
					(size 1.27 1.27)
					(thickness 0.15)
				)
				(justify left bottom)
				(hide yes)
			)
		)
		(property "Footprint" "antmicro-footprints:R_0402_1005Metric"
			(at 256.54 133.35 0)
			(effects
				(font
					(size 1.27 1.27)
					(thickness 0.15)
				)
				(justify left bottom)
				(hide yes)
			)
		)
		(property "Datasheet" "https://industrial.panasonic.com/cdbs/www-data/pdf/RDA0000/AOA0000C301.pdf"
			(at 256.54 135.89 0)
			(effects
				(font
					(size 1.27 1.27)
					(thickness 0.15)
				)
				(justify left bottom)
				(hide yes)
			)
		)
		(property "Description" "SMD Chip Resistor, Jumper, 0 ohm, 100 mW, 0402 [1005 Metric], Thick Film, General Purpose"
			(at 236.22 118.11 0)
			(effects
				(font
					(size 1.27 1.27)
				)
				(hide yes)
			)
		)
		(property "Manufacturer" "Panasonic"
			(at 256.54 140.97 0)
			(effects
				(font
					(size 1.27 1.27)
					(thickness 0.15)
				)
				(justify left bottom)
				(hide yes)
			)
		)
		(property "MPN" "ERJ2GE0R00X"
			(at 256.54 138.43 0)
			(effects
				(font
					(size 1.27 1.27)
					(thickness 0.15)
				)
				(justify left bottom)
				(hide yes)
			)
		)
		(property "Val" "0R"
			(at 242.57 119.38 0)
			(effects
				(font
					(size 1.27 1.27)
					(thickness 0.15)
				)
			)
		)
		(property "License" "Apache-2.0"
			(at 256.54 143.51 0)
			(effects
				(font
					(size 1.27 1.27)
					(thickness 0.15)
				)
				(justify left bottom)
				(hide yes)
			)
		)
		(property "Author" "Antmicro"
			(at 256.54 146.05 0)
			(effects
				(font
					(size 1.27 1.27)
					(thickness 0.15)
				)
				(justify left bottom)
				(hide yes)
			)
		)
		(property "Tolerance" "~"
			(at 256.54 128.27 0)
			(effects
				(font
					(size 1.27 1.27)
				)
				(justify left bottom)
				(hide yes)
			)
		)
		(property "Current" "1A"
			(at 256.54 148.59 0)
			(effects
				(font
					(size 1.27 1.27)
					(thickness 0.15)
				)
				(justify left bottom)
				(hide yes)
			)
		)
		(pin "1"
		)
		(pin "2"
		)
		(instances
			(project "sdi-mipi-video-converter"
				(path ""
					(reference "R129")
					(unit 1)
				)
			)
		)
	)
	(symbol
		(lib_id "antmicroCapacitors0402:C_100n_0402")
		(at 297.18 209.55 90)
		(unit 1)
		(exclude_from_sim no)
		(in_bom yes)
		(on_board yes)
		(dnp no)
		(fields_autoplaced yes)
		(property "Reference" "C122"
			(at 299.72 205.7335 90)
			(effects
				(font
					(size 1.27 1.27)
					(thickness 0.15)
				)
				(justify right)
			)
		)
		(property "Value" "C_100n_0402"
			(at 307.34 189.23 0)
			(effects
				(font
					(size 1.27 1.27)
					(thickness 0.15)
				)
				(justify left bottom)
				(hide yes)
			)
		)
		(property "Footprint" "antmicro-footprints:C_0402_1005Metric"
			(at 309.88 189.23 0)
			(effects
				(font
					(size 1.27 1.27)
					(thickness 0.15)
				)
				(justify left bottom)
				(hide yes)
			)
		)
		(property "Datasheet" "https://www.murata.com/products/productdetail?partno=GRM155R61H104KE14%23"
			(at 312.42 189.23 0)
			(effects
				(font
					(size 1.27 1.27)
					(thickness 0.15)
				)
				(justify left bottom)
				(hide yes)
			)
		)
		(property "Description" "SMD Multilayer Ceramic Capacitor, 0.1 µF, 50 V, 0402 [1005 Metric], ± 10%, X5R, GRM Series"
			(at 297.18 209.55 0)
			(effects
				(font
					(size 1.27 1.27)
				)
				(hide yes)
			)
		)
		(property "Manufacturer" "Murata"
			(at 317.5 189.23 0)
			(effects
				(font
					(size 1.27 1.27)
					(thickness 0.15)
				)
				(justify left bottom)
				(hide yes)
			)
		)
		(property "MPN" "GRM155R61H104KE14D"
			(at 314.96 189.23 0)
			(effects
				(font
					(size 1.27 1.27)
					(thickness 0.15)
				)
				(justify left bottom)
				(hide yes)
			)
		)
		(property "Val" "100n"
			(at 299.72 208.2735 90)
			(effects
				(font
					(size 1.27 1.27)
					(thickness 0.15)
				)
				(justify right)
			)
		)
		(property "License" "Apache-2.0"
			(at 320.04 189.23 0)
			(effects
				(font
					(size 1.27 1.27)
					(thickness 0.15)
				)
				(justify left bottom)
				(hide yes)
			)
		)
		(property "Author" "Antmicro"
			(at 322.58 189.23 0)
			(effects
				(font
					(size 1.27 1.27)
					(thickness 0.15)
				)
				(justify left bottom)
				(hide yes)
			)
		)
		(property "Voltage" "50V"
			(at 325.12 189.23 0)
			(effects
				(font
					(size 1.27 1.27)
				)
				(justify left bottom)
				(hide yes)
			)
		)
		(property "Dielectric" "X5R"
			(at 327.66 189.23 0)
			(effects
				(font
					(size 1.27 1.27)
				)
				(justify left bottom)
				(hide yes)
			)
		)
		(pin "1"
		)
		(pin "2"
		)
		(instances
			(project "sdi-mipi-video-converter"
				(path ""
					(reference "C122")
					(unit 1)
				)
			)
		)
	)
	(symbol
		(lib_id "antmicropower:GND")
		(at 147.32 176.53 0)
		(unit 1)
		(exclude_from_sim no)
		(in_bom yes)
		(on_board yes)
		(dnp no)
		(fields_autoplaced yes)
		(property "Reference" "#PWR0251"
			(at 156.21 179.07 0)
			(effects
				(font
					(size 1.27 1.27)
					(thickness 0.15)
				)
				(justify left bottom)
				(hide yes)
			)
		)
		(property "Value" "GND"
			(at 147.32 181.61 0)
			(effects
				(font
					(size 1.27 1.27)
					(thickness 0.15)
				)
			)
		)
		(property "Footprint" ""
			(at 156.21 184.15 0)
			(effects
				(font
					(size 1.27 1.27)
					(thickness 0.15)
				)
				(justify left bottom)
				(hide yes)
			)
		)
		(property "Datasheet" ""
			(at 156.21 189.23 0)
			(effects
				(font
					(size 1.27 1.27)
					(thickness 0.15)
				)
				(justify left bottom)
				(hide yes)
			)
		)
		(property "Description" ""
			(at 147.32 176.53 0)
			(effects
				(font
					(size 1.27 1.27)
				)
				(hide yes)
			)
		)
		(property "Author" "Antmicro"
			(at 156.21 184.15 0)
			(effects
				(font
					(size 1.27 1.27)
					(thickness 0.15)
				)
				(justify left bottom)
				(hide yes)
			)
		)
		(property "License" "Apache-2.0"
			(at 156.21 186.69 0)
			(effects
				(font
					(size 1.27 1.27)
					(thickness 0.15)
				)
				(justify left bottom)
				(hide yes)
			)
		)
		(pin "1"
		)
		(instances
			(project "sdi-mipi-video-converter"
				(path ""
					(reference "#PWR0251")
					(unit 1)
				)
			)
		)
	)
	(symbol
		(lib_id "antmicroResistors0402:R_5k1_0402")
		(at 271.78 218.44 180)
		(unit 1)
		(exclude_from_sim no)
		(in_bom yes)
		(on_board yes)
		(dnp no)
		(property "Reference" "R11"
			(at 264.795 217.17 0)
			(effects
				(font
					(size 1.27 1.27)
					(thickness 0.15)
				)
			)
		)
		(property "Value" "R_5k1_0402"
			(at 251.46 205.74 0)
			(effects
				(font
					(size 1.27 1.27)
					(thickness 0.15)
				)
				(justify left bottom)
				(hide yes)
			)
		)
		(property "Footprint" "antmicro-footprints:R_0402_1005Metric"
			(at 251.46 203.2 0)
			(effects
				(font
					(size 1.27 1.27)
					(thickness 0.15)
				)
				(justify left bottom)
				(hide yes)
			)
		)
		(property "Datasheet" "https://www.bourns.com/docs/product-datasheets/cr.pdf"
			(at 251.46 200.66 0)
			(effects
				(font
					(size 1.27 1.27)
					(thickness 0.15)
				)
				(justify left bottom)
				(hide yes)
			)
		)
		(property "Description" "SMD Chip Resistor, 5.1 kohm, ± 1%, 63 mW, 0402 [1005 Metric], Thick Film, General Purpose"
			(at 271.78 218.44 0)
			(effects
				(font
					(size 1.27 1.27)
				)
				(hide yes)
			)
		)
		(property "Manufacturer" "Bourns"
			(at 251.46 195.58 0)
			(effects
				(font
					(size 1.27 1.27)
					(thickness 0.15)
				)
				(justify left bottom)
				(hide yes)
			)
		)
		(property "MPN" "CR0402-FX-5101GLF"
			(at 251.46 198.12 0)
			(effects
				(font
					(size 1.27 1.27)
					(thickness 0.15)
				)
				(justify left bottom)
				(hide yes)
			)
		)
		(property "Val" "5k1"
			(at 273.685 217.17 0)
			(effects
				(font
					(size 1.27 1.27)
					(thickness 0.15)
				)
			)
		)
		(property "License" "Apache-2.0"
			(at 251.46 193.04 0)
			(effects
				(font
					(size 1.27 1.27)
					(thickness 0.15)
				)
				(justify left bottom)
				(hide yes)
			)
		)
		(property "Author" "Antmicro"
			(at 251.46 190.5 0)
			(effects
				(font
					(size 1.27 1.27)
					(thickness 0.15)
				)
				(justify left bottom)
				(hide yes)
			)
		)
		(property "Tolerance" "1%"
			(at 251.46 208.28 0)
			(effects
				(font
					(size 1.27 1.27)
				)
				(justify left bottom)
				(hide yes)
			)
		)
		(pin "1"
		)
		(pin "2"
		)
		(instances
			(project "sdi-mipi-video-converter"
				(path ""
					(reference "R11")
					(unit 1)
				)
			)
		)
	)
	(symbol
		(lib_id "antmicropower:GND")
		(at 264.16 250.19 0)
		(unit 1)
		(exclude_from_sim no)
		(in_bom yes)
		(on_board yes)
		(dnp no)
		(fields_autoplaced yes)
		(property "Reference" "#PWR0195"
			(at 273.05 252.73 0)
			(effects
				(font
					(size 1.27 1.27)
					(thickness 0.15)
				)
				(justify left bottom)
				(hide yes)
			)
		)
		(property "Value" "GND"
			(at 264.16 255.27 0)
			(effects
				(font
					(size 1.27 1.27)
					(thickness 0.15)
				)
			)
		)
		(property "Footprint" ""
			(at 273.05 257.81 0)
			(effects
				(font
					(size 1.27 1.27)
					(thickness 0.15)
				)
				(justify left bottom)
				(hide yes)
			)
		)
		(property "Datasheet" ""
			(at 273.05 262.89 0)
			(effects
				(font
					(size 1.27 1.27)
					(thickness 0.15)
				)
				(justify left bottom)
				(hide yes)
			)
		)
		(property "Description" ""
			(at 264.16 250.19 0)
			(effects
				(font
					(size 1.27 1.27)
				)
				(hide yes)
			)
		)
		(property "Author" "Antmicro"
			(at 273.05 257.81 0)
			(effects
				(font
					(size 1.27 1.27)
					(thickness 0.15)
				)
				(justify left bottom)
				(hide yes)
			)
		)
		(property "License" "Apache-2.0"
			(at 273.05 260.35 0)
			(effects
				(font
					(size 1.27 1.27)
					(thickness 0.15)
				)
				(justify left bottom)
				(hide yes)
			)
		)
		(pin "1"
		)
		(instances
			(project "sdi-mipi-video-converter"
				(path ""
					(reference "#PWR0195")
					(unit 1)
				)
			)
		)
	)
	(symbol
		(lib_id "antmicroCapacitors0402:C_100n_0402")
		(at 148.59 227.33 270)
		(mirror x)
		(unit 1)
		(exclude_from_sim no)
		(in_bom yes)
		(on_board yes)
		(dnp no)
		(fields_autoplaced yes)
		(property "Reference" "C109"
			(at 151.13 223.5135 90)
			(effects
				(font
					(size 1.27 1.27)
					(thickness 0.15)
				)
				(justify left)
			)
		)
		(property "Value" "C_100n_0402"
			(at 138.43 207.01 0)
			(effects
				(font
					(size 1.27 1.27)
					(thickness 0.15)
				)
				(justify left bottom)
				(hide yes)
			)
		)
		(property "Footprint" "antmicro-footprints:C_0402_1005Metric"
			(at 135.89 207.01 0)
			(effects
				(font
					(size 1.27 1.27)
					(thickness 0.15)
				)
				(justify left bottom)
				(hide yes)
			)
		)
		(property "Datasheet" "https://www.murata.com/products/productdetail?partno=GRM155R61H104KE14%23"
			(at 133.35 207.01 0)
			(effects
				(font
					(size 1.27 1.27)
					(thickness 0.15)
				)
				(justify left bottom)
				(hide yes)
			)
		)
		(property "Description" "SMD Multilayer Ceramic Capacitor, 0.1 µF, 50 V, 0402 [1005 Metric], ± 10%, X5R, GRM Series"
			(at 148.59 227.33 0)
			(effects
				(font
					(size 1.27 1.27)
				)
				(hide yes)
			)
		)
		(property "Manufacturer" "Murata"
			(at 128.27 207.01 0)
			(effects
				(font
					(size 1.27 1.27)
					(thickness 0.15)
				)
				(justify left bottom)
				(hide yes)
			)
		)
		(property "MPN" "GRM155R61H104KE14D"
			(at 130.81 207.01 0)
			(effects
				(font
					(size 1.27 1.27)
					(thickness 0.15)
				)
				(justify left bottom)
				(hide yes)
			)
		)
		(property "Val" "100n"
			(at 151.13 226.0535 90)
			(effects
				(font
					(size 1.27 1.27)
					(thickness 0.15)
				)
				(justify left)
			)
		)
		(property "License" "Apache-2.0"
			(at 125.73 207.01 0)
			(effects
				(font
					(size 1.27 1.27)
					(thickness 0.15)
				)
				(justify left bottom)
				(hide yes)
			)
		)
		(property "Author" "Antmicro"
			(at 123.19 207.01 0)
			(effects
				(font
					(size 1.27 1.27)
					(thickness 0.15)
				)
				(justify left bottom)
				(hide yes)
			)
		)
		(property "Voltage" "50V"
			(at 120.65 207.01 0)
			(effects
				(font
					(size 1.27 1.27)
				)
				(justify left bottom)
				(hide yes)
			)
		)
		(property "Dielectric" "X5R"
			(at 118.11 207.01 0)
			(effects
				(font
					(size 1.27 1.27)
				)
				(justify left bottom)
				(hide yes)
			)
		)
		(pin "1"
		)
		(pin "2"
		)
		(instances
			(project "sdi-mipi-video-converter"
				(path ""
					(reference "C109")
					(unit 1)
				)
			)
		)
	)
	(symbol
		(lib_id "antmicropower:GND")
		(at 383.54 146.05 0)
		(unit 1)
		(exclude_from_sim no)
		(in_bom yes)
		(on_board yes)
		(dnp no)
		(fields_autoplaced yes)
		(property "Reference" "#PWR0159"
			(at 392.43 148.59 0)
			(effects
				(font
					(size 1.27 1.27)
					(thickness 0.15)
				)
				(justify left bottom)
				(hide yes)
			)
		)
		(property "Value" "GND"
			(at 383.54 151.13 0)
			(effects
				(font
					(size 1.27 1.27)
					(thickness 0.15)
				)
			)
		)
		(property "Footprint" ""
			(at 392.43 153.67 0)
			(effects
				(font
					(size 1.27 1.27)
					(thickness 0.15)
				)
				(justify left bottom)
				(hide yes)
			)
		)
		(property "Datasheet" ""
			(at 392.43 158.75 0)
			(effects
				(font
					(size 1.27 1.27)
					(thickness 0.15)
				)
				(justify left bottom)
				(hide yes)
			)
		)
		(property "Description" ""
			(at 383.54 146.05 0)
			(effects
				(font
					(size 1.27 1.27)
				)
				(hide yes)
			)
		)
		(property "Author" "Antmicro"
			(at 392.43 153.67 0)
			(effects
				(font
					(size 1.27 1.27)
					(thickness 0.15)
				)
				(justify left bottom)
				(hide yes)
			)
		)
		(property "License" "Apache-2.0"
			(at 392.43 156.21 0)
			(effects
				(font
					(size 1.27 1.27)
					(thickness 0.15)
				)
				(justify left bottom)
				(hide yes)
			)
		)
		(pin "1"
		)
		(instances
			(project "sdi-mipi-video-converter"
				(path ""
					(reference "#PWR0159")
					(unit 1)
				)
			)
		)
	)
	(symbol
		(lib_id "antmicroPMICPowerDistributionSwitchesLoadDrivers:DIO7553ST6")
		(at 172.72 222.25 0)
		(unit 1)
		(exclude_from_sim no)
		(in_bom yes)
		(on_board yes)
		(dnp no)
		(fields_autoplaced yes)
		(property "Reference" "U13"
			(at 181.61 214.63 0)
			(effects
				(font
					(size 1.27 1.27)
					(thickness 0.15)
				)
			)
		)
		(property "Value" "DIO7553ST6"
			(at 181.61 217.17 0)
			(effects
				(font
					(size 1.27 1.27)
					(thickness 0.15)
				)
			)
		)
		(property "Footprint" "antmicro-footprints:SOT-23-6"
			(at 204.47 229.87 0)
			(effects
				(font
					(size 1.27 1.27)
					(thickness 0.15)
				)
				(justify left bottom)
				(hide yes)
			)
		)
		(property "Datasheet" "https://www.mouser.com/datasheet/2/802/7e5c577022fb784effcb3cdb25b437c0-1815562.pdf"
			(at 204.47 232.41 0)
			(effects
				(font
					(size 1.27 1.27)
					(thickness 0.15)
				)
				(justify left bottom)
				(hide yes)
			)
		)
		(property "Description" "Power switch"
			(at 172.72 222.25 0)
			(effects
				(font
					(size 1.27 1.27)
				)
				(hide yes)
			)
		)
		(property "MPN" "DIO7553ST6"
			(at 204.47 234.95 0)
			(effects
				(font
					(size 1.27 1.27)
					(thickness 0.15)
				)
				(justify left bottom)
				(hide yes)
			)
		)
		(property "Manufacturer" "DIOO Microcircuits"
			(at 204.47 237.49 0)
			(effects
				(font
					(size 1.27 1.27)
					(thickness 0.15)
				)
				(justify left bottom)
				(hide yes)
			)
		)
		(property "Author" "Antmicro"
			(at 204.47 240.03 0)
			(effects
				(font
					(size 1.27 1.27)
					(thickness 0.15)
				)
				(justify left bottom)
				(hide yes)
			)
		)
		(property "License" "Apache-2.0"
			(at 204.47 242.57 0)
			(effects
				(font
					(size 1.27 1.27)
					(thickness 0.15)
				)
				(justify left bottom)
				(hide yes)
			)
		)
		(pin "1"
		)
		(pin "2"
		)
		(pin "3"
		)
		(pin "4"
		)
		(pin "5"
		)
		(pin "6"
		)
		(instances
			(project "sdi-mipi-video-converter"
				(path ""
					(reference "U13")
					(unit 1)
				)
			)
		)
	)
	(symbol
		(lib_id "antmicroWire2BoardConnectors:JST_SH_1x6_SM06B-SRSS-TB-LF-SN")
		(at 377.19 35.56 0)
		(unit 1)
		(exclude_from_sim no)
		(in_bom yes)
		(on_board yes)
		(dnp no)
		(fields_autoplaced yes)
		(property "Reference" "J9"
			(at 384.81 43.18 0)
			(effects
				(font
					(size 1.27 1.27)
					(thickness 0.15)
				)
				(justify left)
			)
		)
		(property "Value" "JST_GH_1x6_SM06B-SRSS-TB-LF-SN"
			(at 403.86 43.18 0)
			(effects
				(font
					(size 1.27 1.27)
					(thickness 0.15)
				)
				(justify left bottom)
				(hide yes)
			)
		)
		(property "Footprint" "antmicro-footprints:Conn_JST_SH_1x6_SM06B-SRSS-TB-LF-SN"
			(at 403.86 45.72 0)
			(effects
				(font
					(size 1.27 1.27)
					(thickness 0.15)
				)
				(justify left bottom)
				(hide yes)
			)
		)
		(property "Datasheet" "https://www.jst-mfg.com/product/pdf/eng/eSH.pdf"
			(at 403.86 48.26 0)
			(effects
				(font
					(size 1.27 1.27)
					(thickness 0.15)
				)
				(justify left bottom)
				(hide yes)
			)
		)
		(property "Description" "Pin Header, Right Angle, Wire-to-Board, 1 mm, 1 Rows, 6 Contacts, Surface Mount Right Angle, SR"
			(at 377.19 35.56 0)
			(effects
				(font
					(size 1.27 1.27)
				)
				(hide yes)
			)
		)
		(property "MPN" "SM06B-SRSS-TB(LF)(SN)"
			(at 384.81 45.72 0)
			(effects
				(font
					(size 1.27 1.27)
					(thickness 0.15)
				)
				(justify left)
			)
		)
		(property "Manufacturer" "JST Automotive Connectors"
			(at 403.86 50.8 0)
			(effects
				(font
					(size 1.27 1.27)
					(thickness 0.15)
				)
				(justify left bottom)
				(hide yes)
			)
		)
		(property "Author" "Antmicro"
			(at 403.86 53.34 0)
			(effects
				(font
					(size 1.27 1.27)
					(thickness 0.15)
				)
				(justify left bottom)
				(hide yes)
			)
		)
		(property "License" "Apache-2.0"
			(at 403.86 55.88 0)
			(effects
				(font
					(size 1.27 1.27)
					(thickness 0.15)
				)
				(justify left bottom)
				(hide yes)
			)
		)
		(pin "1"
		)
		(pin "2"
		)
		(pin "3"
		)
		(pin "4"
		)
		(pin "5"
		)
		(pin "6"
		)
		(pin "MP"
		)
		(instances
			(project "sdi-mipi-video-converter"
				(path ""
					(reference "J9")
					(unit 1)
				)
			)
		)
	)
	(symbol
		(lib_id "antmicropower:GND")
		(at 105.41 243.84 0)
		(unit 1)
		(exclude_from_sim no)
		(in_bom yes)
		(on_board yes)
		(dnp no)
		(fields_autoplaced yes)
		(property "Reference" "#PWR011"
			(at 114.3 246.38 0)
			(effects
				(font
					(size 1.27 1.27)
					(thickness 0.15)
				)
				(justify left bottom)
				(hide yes)
			)
		)
		(property "Value" "GND"
			(at 105.41 248.92 0)
			(effects
				(font
					(size 1.27 1.27)
					(thickness 0.15)
				)
			)
		)
		(property "Footprint" ""
			(at 114.3 251.46 0)
			(effects
				(font
					(size 1.27 1.27)
					(thickness 0.15)
				)
				(justify left bottom)
				(hide yes)
			)
		)
		(property "Datasheet" ""
			(at 114.3 256.54 0)
			(effects
				(font
					(size 1.27 1.27)
					(thickness 0.15)
				)
				(justify left bottom)
				(hide yes)
			)
		)
		(property "Description" ""
			(at 105.41 243.84 0)
			(effects
				(font
					(size 1.27 1.27)
				)
				(hide yes)
			)
		)
		(property "Author" "Antmicro"
			(at 114.3 251.46 0)
			(effects
				(font
					(size 1.27 1.27)
					(thickness 0.15)
				)
				(justify left bottom)
				(hide yes)
			)
		)
		(property "License" "Apache-2.0"
			(at 114.3 254 0)
			(effects
				(font
					(size 1.27 1.27)
					(thickness 0.15)
				)
				(justify left bottom)
				(hide yes)
			)
		)
		(pin "1"
		)
		(instances
			(project "sdi-mipi-video-converter"
				(path ""
					(reference "#PWR011")
					(unit 1)
				)
			)
		)
	)
	(symbol
		(lib_id "antmicropower:GND")
		(at 193.04 274.32 0)
		(unit 1)
		(exclude_from_sim no)
		(in_bom yes)
		(on_board yes)
		(dnp no)
		(fields_autoplaced yes)
		(property "Reference" "#PWR0259"
			(at 201.93 276.86 0)
			(effects
				(font
					(size 1.27 1.27)
					(thickness 0.15)
				)
				(justify left bottom)
				(hide yes)
			)
		)
		(property "Value" "GND"
			(at 193.04 279.4 0)
			(effects
				(font
					(size 1.27 1.27)
					(thickness 0.15)
				)
			)
		)
		(property "Footprint" ""
			(at 201.93 281.94 0)
			(effects
				(font
					(size 1.27 1.27)
					(thickness 0.15)
				)
				(justify left bottom)
				(hide yes)
			)
		)
		(property "Datasheet" ""
			(at 201.93 287.02 0)
			(effects
				(font
					(size 1.27 1.27)
					(thickness 0.15)
				)
				(justify left bottom)
				(hide yes)
			)
		)
		(property "Description" ""
			(at 193.04 274.32 0)
			(effects
				(font
					(size 1.27 1.27)
				)
				(hide yes)
			)
		)
		(property "Author" "Antmicro"
			(at 201.93 281.94 0)
			(effects
				(font
					(size 1.27 1.27)
					(thickness 0.15)
				)
				(justify left bottom)
				(hide yes)
			)
		)
		(property "License" "Apache-2.0"
			(at 201.93 284.48 0)
			(effects
				(font
					(size 1.27 1.27)
					(thickness 0.15)
				)
				(justify left bottom)
				(hide yes)
			)
		)
		(pin "1"
		)
		(instances
			(project "sdi-mipi-video-converter"
				(path ""
					(reference "#PWR0259")
					(unit 1)
				)
			)
		)
	)
	(symbol
		(lib_id "antmicroResistors0402:R_0R_0402")
		(at 229.87 146.05 180)
		(unit 1)
		(exclude_from_sim no)
		(in_bom yes)
		(on_board yes)
		(dnp no)
		(property "Reference" "R127"
			(at 222.25 147.32 0)
			(effects
				(font
					(size 1.27 1.27)
					(thickness 0.15)
				)
			)
		)
		(property "Value" "R_0R_0402"
			(at 209.55 133.35 0)
			(effects
				(font
					(size 1.27 1.27)
					(thickness 0.15)
				)
				(justify left bottom)
				(hide yes)
			)
		)
		(property "Footprint" "antmicro-footprints:R_0402_1005Metric"
			(at 209.55 130.81 0)
			(effects
				(font
					(size 1.27 1.27)
					(thickness 0.15)
				)
				(justify left bottom)
				(hide yes)
			)
		)
		(property "Datasheet" "https://industrial.panasonic.com/cdbs/www-data/pdf/RDA0000/AOA0000C301.pdf"
			(at 209.55 128.27 0)
			(effects
				(font
					(size 1.27 1.27)
					(thickness 0.15)
				)
				(justify left bottom)
				(hide yes)
			)
		)
		(property "Description" "SMD Chip Resistor, Jumper, 0 ohm, 100 mW, 0402 [1005 Metric], Thick Film, General Purpose"
			(at 229.87 146.05 0)
			(effects
				(font
					(size 1.27 1.27)
				)
				(hide yes)
			)
		)
		(property "Manufacturer" "Panasonic"
			(at 209.55 123.19 0)
			(effects
				(font
					(size 1.27 1.27)
					(thickness 0.15)
				)
				(justify left bottom)
				(hide yes)
			)
		)
		(property "MPN" "ERJ2GE0R00X"
			(at 209.55 125.73 0)
			(effects
				(font
					(size 1.27 1.27)
					(thickness 0.15)
				)
				(justify left bottom)
				(hide yes)
			)
		)
		(property "Val" "0R"
			(at 231.14 147.32 0)
			(effects
				(font
					(size 1.27 1.27)
					(thickness 0.15)
				)
			)
		)
		(property "License" "Apache-2.0"
			(at 209.55 120.65 0)
			(effects
				(font
					(size 1.27 1.27)
					(thickness 0.15)
				)
				(justify left bottom)
				(hide yes)
			)
		)
		(property "Author" "Antmicro"
			(at 209.55 118.11 0)
			(effects
				(font
					(size 1.27 1.27)
					(thickness 0.15)
				)
				(justify left bottom)
				(hide yes)
			)
		)
		(property "Tolerance" "~"
			(at 209.55 135.89 0)
			(effects
				(font
					(size 1.27 1.27)
				)
				(justify left bottom)
				(hide yes)
			)
		)
		(property "Current" "1A"
			(at 209.55 115.57 0)
			(effects
				(font
					(size 1.27 1.27)
					(thickness 0.15)
				)
				(justify left bottom)
				(hide yes)
			)
		)
		(pin "1"
		)
		(pin "2"
		)
		(instances
			(project "sdi-mipi-video-converter"
				(path ""
					(reference "R127")
					(unit 1)
				)
			)
		)
	)
	(symbol
		(lib_id "antmicroGenericPinHeaders:PinHeader_1x6_P2.54mm_SMD_Horizontal")
		(at 381 69.85 0)
		(unit 1)
		(exclude_from_sim no)
		(in_bom no)
		(on_board yes)
		(dnp yes)
		(fields_autoplaced yes)
		(property "Reference" "J10"
			(at 387.35 73.66 0)
			(effects
				(font
					(size 1.27 1.27)
					(thickness 0.15)
				)
				(justify left)
			)
		)
		(property "Value" "PinHeader_1x6_P2.54mm_SMD_Horizontal"
			(at 400.05 78.74 0)
			(effects
				(font
					(size 1.27 1.27)
					(thickness 0.15)
				)
				(justify left bottom)
				(hide yes)
			)
		)
		(property "Footprint" "antmicro-footprints:PinHeader_1x6_P2.54mm_SMD_Horizontal"
			(at 400.05 81.28 0)
			(effects
				(font
					(size 1.27 1.27)
					(thickness 0.15)
				)
				(justify left bottom)
				(hide yes)
			)
		)
		(property "Datasheet" "https://www.mouser.com/datasheet/2/527/tsm-2854655.pdf"
			(at 400.05 83.82 0)
			(effects
				(font
					(size 1.27 1.27)
					(thickness 0.15)
				)
				(justify left bottom)
				(hide yes)
			)
		)
		(property "Description" "Connector Header Surface Mount, Right Angle 6 position 0.100\" (2.54mm)"
			(at 381 69.85 0)
			(effects
				(font
					(size 1.27 1.27)
				)
				(hide yes)
			)
		)
		(property "Manufacturer" "Samtec"
			(at 400.05 86.36 0)
			(effects
				(font
					(size 1.27 1.27)
					(thickness 0.15)
				)
				(justify left bottom)
				(hide yes)
			)
		)
		(property "MPN" "TSM-106-01-T-SH"
			(at 387.35 76.2 0)
			(effects
				(font
					(size 1.27 1.27)
					(thickness 0.15)
				)
				(justify left)
			)
		)
		(property "Author" "Antmicro"
			(at 400.05 88.9 0)
			(effects
				(font
					(size 1.27 1.27)
					(thickness 0.15)
				)
				(justify left bottom)
				(hide yes)
			)
		)
		(property "License" "Apache-2.0"
			(at 400.05 91.44 0)
			(effects
				(font
					(size 1.27 1.27)
					(thickness 0.15)
				)
				(justify left bottom)
				(hide yes)
			)
		)
		(pin "1"
		)
		(pin "2"
		)
		(pin "3"
		)
		(pin "4"
		)
		(pin "5"
		)
		(pin "6"
		)
		(instances
			(project "sdi-mipi-video-converter"
				(path ""
					(reference "J10")
					(unit 1)
				)
			)
		)
	)
	(symbol
		(lib_id "antmicropower:GND")
		(at 284.48 237.49 0)
		(unit 1)
		(exclude_from_sim no)
		(in_bom yes)
		(on_board yes)
		(dnp no)
		(fields_autoplaced yes)
		(property "Reference" "#PWR0241"
			(at 293.37 240.03 0)
			(effects
				(font
					(size 1.27 1.27)
					(thickness 0.15)
				)
				(justify left bottom)
				(hide yes)
			)
		)
		(property "Value" "GND"
			(at 284.48 242.57 0)
			(effects
				(font
					(size 1.27 1.27)
					(thickness 0.15)
				)
			)
		)
		(property "Footprint" ""
			(at 293.37 245.11 0)
			(effects
				(font
					(size 1.27 1.27)
					(thickness 0.15)
				)
				(justify left bottom)
				(hide yes)
			)
		)
		(property "Datasheet" ""
			(at 293.37 250.19 0)
			(effects
				(font
					(size 1.27 1.27)
					(thickness 0.15)
				)
				(justify left bottom)
				(hide yes)
			)
		)
		(property "Description" ""
			(at 284.48 237.49 0)
			(effects
				(font
					(size 1.27 1.27)
				)
				(hide yes)
			)
		)
		(property "Author" "Antmicro"
			(at 293.37 245.11 0)
			(effects
				(font
					(size 1.27 1.27)
					(thickness 0.15)
				)
				(justify left bottom)
				(hide yes)
			)
		)
		(property "License" "Apache-2.0"
			(at 293.37 247.65 0)
			(effects
				(font
					(size 1.27 1.27)
					(thickness 0.15)
				)
				(justify left bottom)
				(hide yes)
			)
		)
		(pin "1"
		)
		(instances
			(project "sdi-mipi-video-converter"
				(path ""
					(reference "#PWR0241")
					(unit 1)
				)
			)
		)
	)
	(symbol
		(lib_id "antmicroLEDIndicationDiscrete:LED_G_0603_LTST-C190GKT")
		(at 147.32 173.99 270)
		(mirror x)
		(unit 1)
		(exclude_from_sim no)
		(in_bom yes)
		(on_board yes)
		(dnp no)
		(property "Reference" "D9"
			(at 151.13 171.4501 90)
			(effects
				(font
					(size 1.27 1.27)
					(thickness 0.15)
				)
				(justify left)
			)
		)
		(property "Value" "LED_G_0603_LTST-C190GKT"
			(at 143.637 186.182 0)
			(effects
				(font
					(size 1.27 1.27)
					(thickness 0.15)
				)
				(justify left)
			)
		)
		(property "Footprint" "antmicro-footprints:LED_0603_1608Metric_G"
			(at 137.16 151.13 0)
			(effects
				(font
					(size 1.27 1.27)
					(thickness 0.15)
				)
				(justify left bottom)
				(hide yes)
			)
		)
		(property "Datasheet" "https://media.digikey.com/pdf/Data%20Sheets/Lite-On%20PDFs/LTST-C190GKT.pdf"
			(at 134.62 151.13 0)
			(effects
				(font
					(size 1.27 1.27)
					(thickness 0.15)
				)
				(justify left bottom)
				(hide yes)
			)
		)
		(property "Description" "LED, Green, SMD, 0603, 20 mA, 2.1 V, 569 nm"
			(at 147.32 173.99 0)
			(effects
				(font
					(size 1.27 1.27)
				)
				(hide yes)
			)
		)
		(property "MPN" "LTST-C190GKT"
			(at 132.08 151.13 0)
			(effects
				(font
					(size 1.27 1.27)
					(thickness 0.15)
				)
				(justify left bottom)
				(hide yes)
			)
		)
		(property "Manufacturer" "Lite-On"
			(at 129.54 151.13 0)
			(effects
				(font
					(size 1.27 1.27)
					(thickness 0.15)
				)
				(justify left bottom)
				(hide yes)
			)
		)
		(property "Author" "Antmicro"
			(at 127 151.13 0)
			(effects
				(font
					(size 1.27 1.27)
					(thickness 0.15)
				)
				(justify left bottom)
				(hide yes)
			)
		)
		(property "License" "Apache-2.0"
			(at 124.46 151.13 0)
			(effects
				(font
					(size 1.27 1.27)
					(thickness 0.15)
				)
				(justify left bottom)
				(hide yes)
			)
		)
		(property "Color" "Green"
			(at 142.24 151.13 0)
			(effects
				(font
					(size 1.27 1.27)
				)
				(justify left bottom)
				(hide yes)
			)
		)
		(pin "1"
		)
		(pin "2"
		)
		(instances
			(project "sdi-mipi-video-converter"
				(path ""
					(reference "D9")
					(unit 1)
				)
			)
		)
	)
	(symbol
		(lib_id "antmicropower:GND")
		(at 110.49 243.84 0)
		(unit 1)
		(exclude_from_sim no)
		(in_bom yes)
		(on_board yes)
		(dnp no)
		(fields_autoplaced yes)
		(property "Reference" "#PWR013"
			(at 119.38 246.38 0)
			(effects
				(font
					(size 1.27 1.27)
					(thickness 0.15)
				)
				(justify left bottom)
				(hide yes)
			)
		)
		(property "Value" "GND"
			(at 110.49 248.92 0)
			(effects
				(font
					(size 1.27 1.27)
					(thickness 0.15)
				)
			)
		)
		(property "Footprint" ""
			(at 119.38 251.46 0)
			(effects
				(font
					(size 1.27 1.27)
					(thickness 0.15)
				)
				(justify left bottom)
				(hide yes)
			)
		)
		(property "Datasheet" ""
			(at 119.38 256.54 0)
			(effects
				(font
					(size 1.27 1.27)
					(thickness 0.15)
				)
				(justify left bottom)
				(hide yes)
			)
		)
		(property "Description" ""
			(at 110.49 243.84 0)
			(effects
				(font
					(size 1.27 1.27)
				)
				(hide yes)
			)
		)
		(property "Author" "Antmicro"
			(at 119.38 251.46 0)
			(effects
				(font
					(size 1.27 1.27)
					(thickness 0.15)
				)
				(justify left bottom)
				(hide yes)
			)
		)
		(property "License" "Apache-2.0"
			(at 119.38 254 0)
			(effects
				(font
					(size 1.27 1.27)
					(thickness 0.15)
				)
				(justify left bottom)
				(hide yes)
			)
		)
		(pin "1"
		)
		(instances
			(project "sdi-mipi-video-converter"
				(path ""
					(reference "#PWR013")
					(unit 1)
				)
			)
		)
	)
	(symbol
		(lib_id "antmicroFPGAChips:CrossLink_LIFCL-40-9BG256C")
		(at 92.71 80.01 0)
		(mirror y)
		(unit 6)
		(exclude_from_sim no)
		(in_bom yes)
		(on_board yes)
		(dnp no)
		(fields_autoplaced yes)
		(property "Reference" "U11"
			(at 64.77 72.39 0)
			(effects
				(font
					(size 1.27 1.27)
					(thickness 0.15)
				)
			)
		)
		(property "Value" "LIFCL-40-9BG256C"
			(at 64.77 72.39 0)
			(effects
				(font
					(size 1.27 1.27)
					(thickness 0.15)
				)
				(hide yes)
			)
		)
		(property "Footprint" "antmicro-footprints:BGA-256_14x14mm_Layout16x16_P0.8mm"
			(at 39.37 87.63 0)
			(effects
				(font
					(size 1.27 1.27)
					(thickness 0.15)
				)
				(justify left bottom)
				(hide yes)
			)
		)
		(property "Datasheet" "https://www.latticesemi.com/-/media/LatticeSemi/Documents/DataSheets/CrossLink/FPGA-DS-02007-2-1-CrossLink-Family-Data-Sheet.ashx?document_id=51662"
			(at 39.37 90.17 0)
			(effects
				(font
					(size 1.27 1.27)
					(thickness 0.15)
				)
				(justify left bottom)
				(hide yes)
			)
		)
		(property "Description" "CrossLink-NX™ Field Programmable Gate Array 256-LFBGA"
			(at 92.71 80.01 0)
			(effects
				(font
					(size 1.27 1.27)
				)
				(hide yes)
			)
		)
		(property "MPN" "LIFCL-40-9BG256C"
			(at 64.77 74.93 0)
			(effects
				(font
					(size 1.27 1.27)
					(thickness 0.15)
				)
			)
		)
		(property "Manufacturer" "Lattice Semiconductor"
			(at 39.37 92.71 0)
			(effects
				(font
					(size 1.27 1.27)
					(thickness 0.15)
				)
				(justify left bottom)
				(hide yes)
			)
		)
		(property "Author" "Antmicro"
			(at 39.37 95.25 0)
			(effects
				(font
					(size 1.27 1.27)
					(thickness 0.15)
				)
				(justify left bottom)
				(hide yes)
			)
		)
		(property "License" "Apache-2.0"
			(at 39.37 97.79 0)
			(effects
				(font
					(size 1.27 1.27)
					(thickness 0.15)
				)
				(justify left bottom)
				(hide yes)
			)
		)
		(pin "B16"
		)
		(pin "C12"
		)
		(pin "C13"
		)
		(pin "C14"
		)
		(pin "C15"
		)
		(pin "C16"
		)
		(pin "D11"
		)
		(pin "D12"
		)
		(pin "D13"
		)
		(pin "D15"
		)
		(pin "D16"
		)
		(pin "E15"
		)
		(pin "E16"
		)
		(pin "D10"
		)
		(pin "E10"
		)
		(pin "E11"
		)
		(pin "E12"
		)
		(pin "E13"
		)
		(pin "E14"
		)
		(pin "E9"
		)
		(pin "F10"
		)
		(pin "F11"
		)
		(pin "F13"
		)
		(pin "F14"
		)
		(pin "F15"
		)
		(pin "F16"
		)
		(pin "F9"
		)
		(pin "G10"
		)
		(pin "G11"
		)
		(pin "G12"
		)
		(pin "G13"
		)
		(pin "G14"
		)
		(pin "G15"
		)
		(pin "G16"
		)
		(pin "G9"
		)
		(pin "H10"
		)
		(pin "H11"
		)
		(pin "H12"
		)
		(pin "H13"
		)
		(pin "H14"
		)
		(pin "H15"
		)
		(pin "H16"
		)
		(pin "J11"
		)
		(pin "J12"
		)
		(pin "J13"
		)
		(pin "J15"
		)
		(pin "J16"
		)
		(pin "K11"
		)
		(pin "K12"
		)
		(pin "L10"
		)
		(pin "L11"
		)
		(pin "L12"
		)
		(pin "M11"
		)
		(pin "M12"
		)
		(pin "M13"
		)
		(pin "M14"
		)
		(pin "M15"
		)
		(pin "M16"
		)
		(pin "N11"
		)
		(pin "N12"
		)
		(pin "N13"
		)
		(pin "N14"
		)
		(pin "N15"
		)
		(pin "N16"
		)
		(pin "P10"
		)
		(pin "P11"
		)
		(pin "P12"
		)
		(pin "P14"
		)
		(pin "P15"
		)
		(pin "P16"
		)
		(pin "R10"
		)
		(pin "R11"
		)
		(pin "R12"
		)
		(pin "R13"
		)
		(pin "R14"
		)
		(pin "R15"
		)
		(pin "R16"
		)
		(pin "T11"
		)
		(pin "T12"
		)
		(pin "T13"
		)
		(pin "T14"
		)
		(pin "T15"
		)
		(pin "L8"
		)
		(pin "L9"
		)
		(pin "M10"
		)
		(pin "M8"
		)
		(pin "M9"
		)
		(pin "N10"
		)
		(pin "N6"
		)
		(pin "N8"
		)
		(pin "N9"
		)
		(pin "P4"
		)
		(pin "P5"
		)
		(pin "P6"
		)
		(pin "P7"
		)
		(pin "P8"
		)
		(pin "P9"
		)
		(pin "R1"
		)
		(pin "R2"
		)
		(pin "R3"
		)
		(pin "R4"
		)
		(pin "R5"
		)
		(pin "R6"
		)
		(pin "R7"
		)
		(pin "R8"
		)
		(pin "R9"
		)
		(pin "T10"
		)
		(pin "T2"
		)
		(pin "T3"
		)
		(pin "T4"
		)
		(pin "T5"
		)
		(pin "T6"
		)
		(pin "T7"
		)
		(pin "T8"
		)
		(pin "T9"
		)
		(pin "K7"
		)
		(pin "L6"
		)
		(pin "L7"
		)
		(pin "M4"
		)
		(pin "M7"
		)
		(pin "N3"
		)
		(pin "N4"
		)
		(pin "N5"
		)
		(pin "P1"
		)
		(pin "P2"
		)
		(pin "P3"
		)
		(pin "H1"
		)
		(pin "H2"
		)
		(pin "H3"
		)
		(pin "H4"
		)
		(pin "H5"
		)
		(pin "H6"
		)
		(pin "J1"
		)
		(pin "J2"
		)
		(pin "J4"
		)
		(pin "J5"
		)
		(pin "J6"
		)
		(pin "K1"
		)
		(pin "K2"
		)
		(pin "K3"
		)
		(pin "K4"
		)
		(pin "K5"
		)
		(pin "K6"
		)
		(pin "L1"
		)
		(pin "L2"
		)
		(pin "L3"
		)
		(pin "L4"
		)
		(pin "L5"
		)
		(pin "M1"
		)
		(pin "M2"
		)
		(pin "M3"
		)
		(pin "N1"
		)
		(pin "N2"
		)
		(pin "D4"
		)
		(pin "D5"
		)
		(pin "D6"
		)
		(pin "E4"
		)
		(pin "E5"
		)
		(pin "E6"
		)
		(pin "F4"
		)
		(pin "F5"
		)
		(pin "F6"
		)
		(pin "G3"
		)
		(pin "G4"
		)
		(pin "G6"
		)
		(pin "B1"
		)
		(pin "B2"
		)
		(pin "C1"
		)
		(pin "C2"
		)
		(pin "D1"
		)
		(pin "D2"
		)
		(pin "E1"
		)
		(pin "E2"
		)
		(pin "F1"
		)
		(pin "F2"
		)
		(pin "A3"
		)
		(pin "A4"
		)
		(pin "A5"
		)
		(pin "A6"
		)
		(pin "A7"
		)
		(pin "B3"
		)
		(pin "B4"
		)
		(pin "B5"
		)
		(pin "B6"
		)
		(pin "B7"
		)
		(pin "K13"
		)
		(pin "K14"
		)
		(pin "K15"
		)
		(pin "K16"
		)
		(pin "L13"
		)
		(pin "L14"
		)
		(pin "L15"
		)
		(pin "L16"
		)
		(pin "A11"
		)
		(pin "A12"
		)
		(pin "A14"
		)
		(pin "A15"
		)
		(pin "A9"
		)
		(pin "B12"
		)
		(pin "B9"
		)
		(pin "C11"
		)
		(pin "A1"
		)
		(pin "A10"
		)
		(pin "A13"
		)
		(pin "A16"
		)
		(pin "A2"
		)
		(pin "A8"
		)
		(pin "B10"
		)
		(pin "B11"
		)
		(pin "B13"
		)
		(pin "B14"
		)
		(pin "B15"
		)
		(pin "B8"
		)
		(pin "C10"
		)
		(pin "C3"
		)
		(pin "C4"
		)
		(pin "C5"
		)
		(pin "C6"
		)
		(pin "C7"
		)
		(pin "C8"
		)
		(pin "C9"
		)
		(pin "D14"
		)
		(pin "D3"
		)
		(pin "D7"
		)
		(pin "D8"
		)
		(pin "D9"
		)
		(pin "E3"
		)
		(pin "E7"
		)
		(pin "E8"
		)
		(pin "F12"
		)
		(pin "F3"
		)
		(pin "F7"
		)
		(pin "F8"
		)
		(pin "G1"
		)
		(pin "G2"
		)
		(pin "G5"
		)
		(pin "G7"
		)
		(pin "G8"
		)
		(pin "H7"
		)
		(pin "H8"
		)
		(pin "H9"
		)
		(pin "J10"
		)
		(pin "J14"
		)
		(pin "J3"
		)
		(pin "J7"
		)
		(pin "J8"
		)
		(pin "J9"
		)
		(pin "K10"
		)
		(pin "K8"
		)
		(pin "K9"
		)
		(pin "M5"
		)
		(pin "M6"
		)
		(pin "N7"
		)
		(pin "P13"
		)
		(pin "T1"
		)
		(pin "T16"
		)
		(instances
			(project "sdi-mipi-video-converter"
				(path ""
					(reference "U11")
					(unit 6)
				)
			)
		)
	)
	(symbol
		(lib_id "antmicroResistors0402:R_0R_0402")
		(at 181.61 133.35 180)
		(unit 1)
		(exclude_from_sim no)
		(in_bom yes)
		(on_board yes)
		(dnp no)
		(property "Reference" "R123"
			(at 173.99 134.62 0)
			(effects
				(font
					(size 1.27 1.27)
					(thickness 0.15)
				)
			)
		)
		(property "Value" "R_0R_0402"
			(at 161.29 120.65 0)
			(effects
				(font
					(size 1.27 1.27)
					(thickness 0.15)
				)
				(justify left bottom)
				(hide yes)
			)
		)
		(property "Footprint" "antmicro-footprints:R_0402_1005Metric"
			(at 161.29 118.11 0)
			(effects
				(font
					(size 1.27 1.27)
					(thickness 0.15)
				)
				(justify left bottom)
				(hide yes)
			)
		)
		(property "Datasheet" "https://industrial.panasonic.com/cdbs/www-data/pdf/RDA0000/AOA0000C301.pdf"
			(at 161.29 115.57 0)
			(effects
				(font
					(size 1.27 1.27)
					(thickness 0.15)
				)
				(justify left bottom)
				(hide yes)
			)
		)
		(property "Description" "SMD Chip Resistor, Jumper, 0 ohm, 100 mW, 0402 [1005 Metric], Thick Film, General Purpose"
			(at 181.61 133.35 0)
			(effects
				(font
					(size 1.27 1.27)
				)
				(hide yes)
			)
		)
		(property "Manufacturer" "Panasonic"
			(at 161.29 110.49 0)
			(effects
				(font
					(size 1.27 1.27)
					(thickness 0.15)
				)
				(justify left bottom)
				(hide yes)
			)
		)
		(property "MPN" "ERJ2GE0R00X"
			(at 161.29 113.03 0)
			(effects
				(font
					(size 1.27 1.27)
					(thickness 0.15)
				)
				(justify left bottom)
				(hide yes)
			)
		)
		(property "Val" "0R"
			(at 182.88 134.62 0)
			(effects
				(font
					(size 1.27 1.27)
					(thickness 0.15)
				)
			)
		)
		(property "License" "Apache-2.0"
			(at 161.29 107.95 0)
			(effects
				(font
					(size 1.27 1.27)
					(thickness 0.15)
				)
				(justify left bottom)
				(hide yes)
			)
		)
		(property "Author" "Antmicro"
			(at 161.29 105.41 0)
			(effects
				(font
					(size 1.27 1.27)
					(thickness 0.15)
				)
				(justify left bottom)
				(hide yes)
			)
		)
		(property "Tolerance" "~"
			(at 161.29 123.19 0)
			(effects
				(font
					(size 1.27 1.27)
				)
				(justify left bottom)
				(hide yes)
			)
		)
		(property "Current" "1A"
			(at 161.29 102.87 0)
			(effects
				(font
					(size 1.27 1.27)
					(thickness 0.15)
				)
				(justify left bottom)
				(hide yes)
			)
		)
		(pin "1"
		)
		(pin "2"
		)
		(instances
			(project "sdi-mipi-video-converter"
				(path ""
					(reference "R123")
					(unit 1)
				)
			)
		)
	)
	(symbol
		(lib_id "antmicroCapacitors0603:C_1u_0603")
		(at 170.18 171.45 90)
		(unit 1)
		(exclude_from_sim no)
		(in_bom yes)
		(on_board yes)
		(dnp no)
		(fields_autoplaced yes)
		(property "Reference" "C111"
			(at 172.72 167.6335 90)
			(effects
				(font
					(size 1.27 1.27)
					(thickness 0.15)
				)
				(justify right)
			)
		)
		(property "Value" "C_1u_0603"
			(at 180.34 151.13 0)
			(effects
				(font
					(size 1.27 1.27)
					(thickness 0.15)
				)
				(justify left bottom)
				(hide yes)
			)
		)
		(property "Footprint" "antmicro-footprints:C_0603_1608Metric"
			(at 182.88 151.13 0)
			(effects
				(font
					(size 1.27 1.27)
					(thickness 0.15)
				)
				(justify left bottom)
				(hide yes)
			)
		)
		(property "Datasheet" "https://spicat.kyocera-avx.com/product/mlcc/chartview/0603YD105KAT2A/"
			(at 185.42 151.13 0)
			(effects
				(font
					(size 1.27 1.27)
					(thickness 0.15)
				)
				(justify left bottom)
				(hide yes)
			)
		)
		(property "Description" "SMD Multilayer Ceramic Capacitor, 1 µF, 16 V, 0603 [1608 Metric], ± 10%, X5R, AVX 0603 MLCC"
			(at 170.18 171.45 0)
			(effects
				(font
					(size 1.27 1.27)
				)
				(hide yes)
			)
		)
		(property "Manufacturer" "KYOCERA AVX"
			(at 190.5 151.13 0)
			(effects
				(font
					(size 1.27 1.27)
					(thickness 0.15)
				)
				(justify left bottom)
				(hide yes)
			)
		)
		(property "MPN" "0603YD105KAT2A"
			(at 187.96 151.13 0)
			(effects
				(font
					(size 1.27 1.27)
					(thickness 0.15)
				)
				(justify left bottom)
				(hide yes)
			)
		)
		(property "Val" "1u"
			(at 172.72 170.1735 90)
			(effects
				(font
					(size 1.27 1.27)
					(thickness 0.15)
				)
				(justify right)
			)
		)
		(property "License" "Apache-2.0"
			(at 193.04 151.13 0)
			(effects
				(font
					(size 1.27 1.27)
					(thickness 0.15)
				)
				(justify left bottom)
				(hide yes)
			)
		)
		(property "Author" "Antmicro"
			(at 195.58 151.13 0)
			(effects
				(font
					(size 1.27 1.27)
					(thickness 0.15)
				)
				(justify left bottom)
				(hide yes)
			)
		)
		(property "Voltage" ""
			(at 198.12 151.13 0)
			(effects
				(font
					(size 1.27 1.27)
				)
				(justify left bottom)
				(hide yes)
			)
		)
		(property "Dielectric" ""
			(at 200.66 151.13 0)
			(effects
				(font
					(size 1.27 1.27)
				)
				(justify left bottom)
				(hide yes)
			)
		)
		(pin "1"
		)
		(pin "2"
		)
		(instances
			(project "sdi-mipi-video-converter"
				(path ""
					(reference "C111")
					(unit 1)
				)
			)
		)
	)
	(symbol
		(lib_id "antmicropower:GND")
		(at 313.69 242.57 0)
		(unit 1)
		(exclude_from_sim no)
		(in_bom yes)
		(on_board yes)
		(dnp no)
		(fields_autoplaced yes)
		(property "Reference" "#PWR0183"
			(at 322.58 245.11 0)
			(effects
				(font
					(size 1.27 1.27)
					(thickness 0.15)
				)
				(justify left bottom)
				(hide yes)
			)
		)
		(property "Value" "GND"
			(at 313.69 247.65 0)
			(effects
				(font
					(size 1.27 1.27)
					(thickness 0.15)
				)
			)
		)
		(property "Footprint" ""
			(at 322.58 250.19 0)
			(effects
				(font
					(size 1.27 1.27)
					(thickness 0.15)
				)
				(justify left bottom)
				(hide yes)
			)
		)
		(property "Datasheet" ""
			(at 322.58 255.27 0)
			(effects
				(font
					(size 1.27 1.27)
					(thickness 0.15)
				)
				(justify left bottom)
				(hide yes)
			)
		)
		(property "Description" ""
			(at 313.69 242.57 0)
			(effects
				(font
					(size 1.27 1.27)
				)
				(hide yes)
			)
		)
		(property "Author" "Antmicro"
			(at 322.58 250.19 0)
			(effects
				(font
					(size 1.27 1.27)
					(thickness 0.15)
				)
				(justify left bottom)
				(hide yes)
			)
		)
		(property "License" "Apache-2.0"
			(at 322.58 252.73 0)
			(effects
				(font
					(size 1.27 1.27)
					(thickness 0.15)
				)
				(justify left bottom)
				(hide yes)
			)
		)
		(pin "1"
		)
		(instances
			(project "sdi-mipi-video-converter"
				(path ""
					(reference "#PWR0183")
					(unit 1)
				)
			)
		)
	)
	(symbol
		(lib_id "antmicropower:+3.3V")
		(at 342.9 33.02 0)
		(unit 1)
		(exclude_from_sim no)
		(in_bom yes)
		(on_board yes)
		(dnp no)
		(fields_autoplaced yes)
		(property "Reference" "#PWR0264"
			(at 342.9 36.83 0)
			(effects
				(font
					(size 1.27 1.27)
				)
				(hide yes)
			)
		)
		(property "Value" "+3V3"
			(at 342.9 27.94 0)
			(effects
				(font
					(size 1.27 1.27)
				)
			)
		)
		(property "Footprint" ""
			(at 342.9 33.02 0)
			(effects
				(font
					(size 1.27 1.27)
				)
				(hide yes)
			)
		)
		(property "Datasheet" ""
			(at 342.9 33.02 0)
			(effects
				(font
					(size 1.27 1.27)
				)
				(hide yes)
			)
		)
		(property "Description" ""
			(at 342.9 33.02 0)
			(effects
				(font
					(size 1.27 1.27)
				)
				(hide yes)
			)
		)
		(pin "1"
		)
		(instances
			(project "sdi-mipi-video-converter"
				(path ""
					(reference "#PWR0264")
					(unit 1)
				)
			)
		)
	)
	(symbol
		(lib_id "antmicroCapacitors0402:C_47p_0402")
		(at 284.48 236.22 90)
		(unit 1)
		(exclude_from_sim no)
		(in_bom yes)
		(on_board yes)
		(dnp no)
		(fields_autoplaced yes)
		(property "Reference" "C121"
			(at 287.02 232.4035 90)
			(effects
				(font
					(size 1.27 1.27)
					(thickness 0.15)
				)
				(justify right)
			)
		)
		(property "Value" "C_47p_0402"
			(at 294.64 215.9 0)
			(effects
				(font
					(size 1.27 1.27)
					(thickness 0.15)
				)
				(justify left bottom)
				(hide yes)
			)
		)
		(property "Footprint" "antmicro-footprints:C_0402_1005Metric"
			(at 297.18 215.9 0)
			(effects
				(font
					(size 1.27 1.27)
					(thickness 0.15)
				)
				(justify left bottom)
				(hide yes)
			)
		)
		(property "Datasheet" "https://www.kemet.com/en/us/capacitors/product/C0402C470J5GACTU.html"
			(at 299.72 215.9 0)
			(effects
				(font
					(size 1.27 1.27)
					(thickness 0.15)
				)
				(justify left bottom)
				(hide yes)
			)
		)
		(property "Description" "SMD Multilayer Ceramic Capacitor, 47 pF, 50 V, 0402 [1005 Metric], ± 5%, C0G / NP0, C Series KEMET"
			(at 284.48 236.22 0)
			(effects
				(font
					(size 1.27 1.27)
				)
				(hide yes)
			)
		)
		(property "Manufacturer" "KEMET"
			(at 304.8 215.9 0)
			(effects
				(font
					(size 1.27 1.27)
					(thickness 0.15)
				)
				(justify left bottom)
				(hide yes)
			)
		)
		(property "MPN" "C0402C470J5GACTU"
			(at 302.26 215.9 0)
			(effects
				(font
					(size 1.27 1.27)
					(thickness 0.15)
				)
				(justify left bottom)
				(hide yes)
			)
		)
		(property "Val" "47p"
			(at 287.02 234.9435 90)
			(effects
				(font
					(size 1.27 1.27)
					(thickness 0.15)
				)
				(justify right)
			)
		)
		(property "License" "Apache-2.0"
			(at 307.34 215.9 0)
			(effects
				(font
					(size 1.27 1.27)
					(thickness 0.15)
				)
				(justify left bottom)
				(hide yes)
			)
		)
		(property "Author" "Antmicro"
			(at 309.88 215.9 0)
			(effects
				(font
					(size 1.27 1.27)
					(thickness 0.15)
				)
				(justify left bottom)
				(hide yes)
			)
		)
		(property "Voltage" ""
			(at 312.42 215.9 0)
			(effects
				(font
					(size 1.27 1.27)
				)
				(justify left bottom)
				(hide yes)
			)
		)
		(property "Dielectric" "C0G"
			(at 314.96 215.9 0)
			(effects
				(font
					(size 1.27 1.27)
				)
				(justify left bottom)
				(hide yes)
			)
		)
		(pin "1"
		)
		(pin "2"
		)
		(instances
			(project "sdi-mipi-video-converter"
				(path ""
					(reference "C121")
					(unit 1)
				)
			)
		)
	)
	(symbol
		(lib_id "antmicroResistors0402:R_0R_0402")
		(at 231.14 135.89 180)
		(unit 1)
		(exclude_from_sim no)
		(in_bom yes)
		(on_board yes)
		(dnp no)
		(property "Reference" "R110"
			(at 223.52 137.16 0)
			(effects
				(font
					(size 1.27 1.27)
					(thickness 0.15)
				)
			)
		)
		(property "Value" "R_0R_0402"
			(at 210.82 123.19 0)
			(effects
				(font
					(size 1.27 1.27)
					(thickness 0.15)
				)
				(justify left bottom)
				(hide yes)
			)
		)
		(property "Footprint" "antmicro-footprints:R_0402_1005Metric"
			(at 210.82 120.65 0)
			(effects
				(font
					(size 1.27 1.27)
					(thickness 0.15)
				)
				(justify left bottom)
				(hide yes)
			)
		)
		(property "Datasheet" "https://industrial.panasonic.com/cdbs/www-data/pdf/RDA0000/AOA0000C301.pdf"
			(at 210.82 118.11 0)
			(effects
				(font
					(size 1.27 1.27)
					(thickness 0.15)
				)
				(justify left bottom)
				(hide yes)
			)
		)
		(property "Description" "SMD Chip Resistor, Jumper, 0 ohm, 100 mW, 0402 [1005 Metric], Thick Film, General Purpose"
			(at 231.14 135.89 0)
			(effects
				(font
					(size 1.27 1.27)
				)
				(hide yes)
			)
		)
		(property "Manufacturer" "Panasonic"
			(at 210.82 113.03 0)
			(effects
				(font
					(size 1.27 1.27)
					(thickness 0.15)
				)
				(justify left bottom)
				(hide yes)
			)
		)
		(property "MPN" "ERJ2GE0R00X"
			(at 210.82 115.57 0)
			(effects
				(font
					(size 1.27 1.27)
					(thickness 0.15)
				)
				(justify left bottom)
				(hide yes)
			)
		)
		(property "Val" "0R"
			(at 232.41 137.16 0)
			(effects
				(font
					(size 1.27 1.27)
					(thickness 0.15)
				)
			)
		)
		(property "License" "Apache-2.0"
			(at 210.82 110.49 0)
			(effects
				(font
					(size 1.27 1.27)
					(thickness 0.15)
				)
				(justify left bottom)
				(hide yes)
			)
		)
		(property "Author" "Antmicro"
			(at 210.82 107.95 0)
			(effects
				(font
					(size 1.27 1.27)
					(thickness 0.15)
				)
				(justify left bottom)
				(hide yes)
			)
		)
		(property "Tolerance" "~"
			(at 210.82 125.73 0)
			(effects
				(font
					(size 1.27 1.27)
				)
				(justify left bottom)
				(hide yes)
			)
		)
		(property "Current" "1A"
			(at 210.82 105.41 0)
			(effects
				(font
					(size 1.27 1.27)
					(thickness 0.15)
				)
				(justify left bottom)
				(hide yes)
			)
		)
		(pin "1"
		)
		(pin "2"
		)
		(instances
			(project "sdi-mipi-video-converter"
				(path ""
					(reference "R110")
					(unit 1)
				)
			)
		)
	)
	(symbol
		(lib_id "antmicroResistors0603:R_200R_0603")
		(at 147.32 166.37 90)
		(unit 1)
		(exclude_from_sim no)
		(in_bom yes)
		(on_board yes)
		(dnp no)
		(property "Reference" "R102"
			(at 148.59 162.56 90)
			(effects
				(font
					(size 1.27 1.27)
					(thickness 0.15)
				)
				(justify right)
			)
		)
		(property "Value" "R_200R_0603"
			(at 160.02 146.05 0)
			(effects
				(font
					(size 1.27 1.27)
					(thickness 0.15)
				)
				(justify left bottom)
				(hide yes)
			)
		)
		(property "Footprint" "antmicro-footprints:R_0603_1608Metric"
			(at 162.56 146.05 0)
			(effects
				(font
					(size 1.27 1.27)
					(thickness 0.15)
				)
				(justify left bottom)
				(hide yes)
			)
		)
		(property "Datasheet" "https://www.bourns.com/docs/product-datasheets/cr.pdf"
			(at 165.1 146.05 0)
			(effects
				(font
					(size 1.27 1.27)
					(thickness 0.15)
				)
				(justify left bottom)
				(hide yes)
			)
		)
		(property "Description" "SMD Chip Resistor, 200 ohm, ± 1%, 100 mW, 0603 [1608 Metric], Thick Film, General Purpose"
			(at 147.32 166.37 0)
			(effects
				(font
					(size 1.27 1.27)
				)
				(hide yes)
			)
		)
		(property "Manufacturer" "Bourns"
			(at 170.18 146.05 0)
			(effects
				(font
					(size 1.27 1.27)
					(thickness 0.15)
				)
				(justify left bottom)
				(hide yes)
			)
		)
		(property "MPN" "CR0603-FX-2000ELF"
			(at 167.64 146.05 0)
			(effects
				(font
					(size 1.27 1.27)
					(thickness 0.15)
				)
				(justify left bottom)
				(hide yes)
			)
		)
		(property "Val" "200R"
			(at 148.59 165.1 90)
			(effects
				(font
					(size 1.27 1.27)
					(thickness 0.15)
				)
				(justify right)
			)
		)
		(property "License" "Apache-2.0"
			(at 172.72 146.05 0)
			(effects
				(font
					(size 1.27 1.27)
					(thickness 0.15)
				)
				(justify left bottom)
				(hide yes)
			)
		)
		(property "Author" "Antmicro"
			(at 175.26 146.05 0)
			(effects
				(font
					(size 1.27 1.27)
					(thickness 0.15)
				)
				(justify left bottom)
				(hide yes)
			)
		)
		(property "Tolerance" "1%"
			(at 157.48 146.05 0)
			(effects
				(font
					(size 1.27 1.27)
				)
				(justify left bottom)
				(hide yes)
			)
		)
		(pin "1"
		)
		(pin "2"
		)
		(instances
			(project "sdi-mipi-video-converter"
				(path ""
					(reference "R102")
					(unit 1)
				)
			)
		)
	)
	(symbol
		(lib_id "antmicropower:+1V2")
		(at 111.76 78.74 0)
		(unit 1)
		(exclude_from_sim no)
		(in_bom yes)
		(on_board yes)
		(dnp no)
		(fields_autoplaced yes)
		(property "Reference" "#PWR0148"
			(at 111.76 82.55 0)
			(effects
				(font
					(size 1.27 1.27)
				)
				(hide yes)
			)
		)
		(property "Value" "+1V2"
			(at 111.76 73.66 0)
			(effects
				(font
					(size 1.27 1.27)
				)
			)
		)
		(property "Footprint" ""
			(at 111.76 78.74 0)
			(effects
				(font
					(size 1.27 1.27)
				)
				(hide yes)
			)
		)
		(property "Datasheet" ""
			(at 111.76 78.74 0)
			(effects
				(font
					(size 1.27 1.27)
				)
				(hide yes)
			)
		)
		(property "Description" ""
			(at 111.76 78.74 0)
			(effects
				(font
					(size 1.27 1.27)
				)
				(hide yes)
			)
		)
		(pin "1"
		)
		(instances
			(project "sdi-mipi-video-converter"
				(path ""
					(reference "#PWR0148")
					(unit 1)
				)
			)
		)
	)
	(symbol
		(lib_id "antmicroFuses:F_1.25A_0603")
		(at 347.98 35.56 0)
		(unit 1)
		(exclude_from_sim no)
		(in_bom yes)
		(on_board yes)
		(dnp no)
		(fields_autoplaced yes)
		(property "Reference" "F1"
			(at 350.52 30.48 0)
			(effects
				(font
					(size 1.27 1.27)
					(thickness 0.15)
				)
			)
		)
		(property "Value" "F_1.25A_0603"
			(at 372.11 40.64 0)
			(effects
				(font
					(size 1.27 1.27)
					(thickness 0.15)
				)
				(justify left bottom)
				(hide yes)
			)
		)
		(property "Footprint" "antmicro-footprints:F_0603_1608Metric"
			(at 372.11 43.18 0)
			(effects
				(font
					(size 1.27 1.27)
					(thickness 0.15)
				)
				(justify left bottom)
				(hide yes)
			)
		)
		(property "Datasheet" "https://www.littelfuse.com/~/media/electronics/datasheets/fuses/littelfuse_fuse_467_datasheet.pdf.pdf"
			(at 372.11 45.72 0)
			(effects
				(font
					(size 1.27 1.27)
					(thickness 0.15)
				)
				(justify left bottom)
				(hide yes)
			)
		)
		(property "Description" "Fuse, Surface Mount, 1.25 A, Very Fast Acting, 32 V, 32 V, 0603 (1608 Metric), 467"
			(at 347.98 35.56 0)
			(effects
				(font
					(size 1.27 1.27)
				)
				(hide yes)
			)
		)
		(property "MPN" "04671.25NR"
			(at 350.52 33.02 0)
			(effects
				(font
					(size 1.27 1.27)
					(thickness 0.15)
				)
			)
		)
		(property "Manufacturer" "Littelfuse"
			(at 372.11 50.8 0)
			(effects
				(font
					(size 1.27 1.27)
					(thickness 0.15)
				)
				(justify left bottom)
				(hide yes)
			)
		)
		(property "Author" "Antmicro"
			(at 372.11 53.34 0)
			(effects
				(font
					(size 1.27 1.27)
					(thickness 0.15)
				)
				(justify left bottom)
				(hide yes)
			)
		)
		(property "License" "Apache-2.0"
			(at 372.11 55.88 0)
			(effects
				(font
					(size 1.27 1.27)
					(thickness 0.15)
				)
				(justify left bottom)
				(hide yes)
			)
		)
		(pin "1"
		)
		(pin "2"
		)
		(instances
			(project "sdi-mipi-video-converter"
				(path ""
					(reference "F1")
					(unit 1)
				)
			)
		)
	)
	(symbol
		(lib_id "antmicroResistors0603:R_10k_0603")
		(at 71.12 232.41 90)
		(mirror x)
		(unit 1)
		(exclude_from_sim no)
		(in_bom yes)
		(on_board yes)
		(dnp no)
		(property "Reference" "R114"
			(at 72.39 233.68 90)
			(effects
				(font
					(size 1.27 1.27)
					(thickness 0.15)
				)
				(justify right)
			)
		)
		(property "Value" "R_10k_0603"
			(at 83.82 252.73 0)
			(effects
				(font
					(size 1.27 1.27)
					(thickness 0.15)
				)
				(justify left bottom)
				(hide yes)
			)
		)
		(property "Footprint" "antmicro-footprints:R_0603_1608Metric"
			(at 86.36 252.73 0)
			(effects
				(font
					(size 1.27 1.27)
					(thickness 0.15)
				)
				(justify left bottom)
				(hide yes)
			)
		)
		(property "Datasheet" "https://www.bourns.com/docs/product-datasheets/cr.pdf"
			(at 88.9 252.73 0)
			(effects
				(font
					(size 1.27 1.27)
					(thickness 0.15)
				)
				(justify left bottom)
				(hide yes)
			)
		)
		(property "Description" "SMD Chip Resistor, 10 kohm, ± 1%, 100 mW, 0603 [1608 Metric], Thick Film, General Purpose"
			(at 71.12 232.41 0)
			(effects
				(font
					(size 1.27 1.27)
				)
				(hide yes)
			)
		)
		(property "Manufacturer" "Bourns"
			(at 93.98 252.73 0)
			(effects
				(font
					(size 1.27 1.27)
					(thickness 0.15)
				)
				(justify left bottom)
				(hide yes)
			)
		)
		(property "MPN" "CR0603-FX-1002ELF"
			(at 91.44 252.73 0)
			(effects
				(font
					(size 1.27 1.27)
					(thickness 0.15)
				)
				(justify left bottom)
				(hide yes)
			)
		)
		(property "Val" "10k"
			(at 72.39 236.22 90)
			(effects
				(font
					(size 1.27 1.27)
					(thickness 0.15)
				)
				(justify right)
			)
		)
		(property "License" "Apache-2.0"
			(at 96.52 252.73 0)
			(effects
				(font
					(size 1.27 1.27)
					(thickness 0.15)
				)
				(justify left bottom)
				(hide yes)
			)
		)
		(property "Author" "Antmicro"
			(at 99.06 252.73 0)
			(effects
				(font
					(size 1.27 1.27)
					(thickness 0.15)
				)
				(justify left bottom)
				(hide yes)
			)
		)
		(property "Tolerance" "1%"
			(at 81.28 252.73 0)
			(effects
				(font
					(size 1.27 1.27)
				)
				(justify left bottom)
				(hide yes)
			)
		)
		(pin "1"
		)
		(pin "2"
		)
		(instances
			(project "sdi-mipi-video-converter"
				(path ""
					(reference "R114")
					(unit 1)
				)
			)
		)
	)
	(symbol
		(lib_id "antmicropower:GND")
		(at 191.77 168.91 0)
		(unit 1)
		(exclude_from_sim no)
		(in_bom yes)
		(on_board yes)
		(dnp no)
		(fields_autoplaced yes)
		(property "Reference" "#PWR0154"
			(at 200.66 171.45 0)
			(effects
				(font
					(size 1.27 1.27)
					(thickness 0.15)
				)
				(justify left bottom)
				(hide yes)
			)
		)
		(property "Value" "GND"
			(at 191.77 173.99 0)
			(effects
				(font
					(size 1.27 1.27)
					(thickness 0.15)
				)
			)
		)
		(property "Footprint" ""
			(at 200.66 176.53 0)
			(effects
				(font
					(size 1.27 1.27)
					(thickness 0.15)
				)
				(justify left bottom)
				(hide yes)
			)
		)
		(property "Datasheet" ""
			(at 200.66 181.61 0)
			(effects
				(font
					(size 1.27 1.27)
					(thickness 0.15)
				)
				(justify left bottom)
				(hide yes)
			)
		)
		(property "Description" ""
			(at 191.77 168.91 0)
			(effects
				(font
					(size 1.27 1.27)
				)
				(hide yes)
			)
		)
		(property "Author" "Antmicro"
			(at 200.66 176.53 0)
			(effects
				(font
					(size 1.27 1.27)
					(thickness 0.15)
				)
				(justify left bottom)
				(hide yes)
			)
		)
		(property "License" "Apache-2.0"
			(at 200.66 179.07 0)
			(effects
				(font
					(size 1.27 1.27)
					(thickness 0.15)
				)
				(justify left bottom)
				(hide yes)
			)
		)
		(pin "1"
		)
		(instances
			(project "sdi-mipi-video-converter"
				(path ""
					(reference "#PWR0154")
					(unit 1)
				)
			)
		)
	)
	(symbol
		(lib_id "antmicroPMICPowerDistributionSwitchesLoadDrivers:DIO7553ST6")
		(at 172.72 260.35 0)
		(unit 1)
		(exclude_from_sim no)
		(in_bom yes)
		(on_board yes)
		(dnp no)
		(fields_autoplaced yes)
		(property "Reference" "U14"
			(at 181.61 252.73 0)
			(effects
				(font
					(size 1.27 1.27)
					(thickness 0.15)
				)
			)
		)
		(property "Value" "DIO7553ST6"
			(at 181.61 255.27 0)
			(effects
				(font
					(size 1.27 1.27)
					(thickness 0.15)
				)
			)
		)
		(property "Footprint" "antmicro-footprints:SOT-23-6"
			(at 204.47 267.97 0)
			(effects
				(font
					(size 1.27 1.27)
					(thickness 0.15)
				)
				(justify left bottom)
				(hide yes)
			)
		)
		(property "Datasheet" "https://www.mouser.com/datasheet/2/802/7e5c577022fb784effcb3cdb25b437c0-1815562.pdf"
			(at 204.47 270.51 0)
			(effects
				(font
					(size 1.27 1.27)
					(thickness 0.15)
				)
				(justify left bottom)
				(hide yes)
			)
		)
		(property "Description" "Power switch"
			(at 172.72 260.35 0)
			(effects
				(font
					(size 1.27 1.27)
				)
				(hide yes)
			)
		)
		(property "MPN" "DIO7553ST6"
			(at 204.47 273.05 0)
			(effects
				(font
					(size 1.27 1.27)
					(thickness 0.15)
				)
				(justify left bottom)
				(hide yes)
			)
		)
		(property "Manufacturer" "DIOO Microcircuits"
			(at 204.47 275.59 0)
			(effects
				(font
					(size 1.27 1.27)
					(thickness 0.15)
				)
				(justify left bottom)
				(hide yes)
			)
		)
		(property "Author" "Antmicro"
			(at 204.47 278.13 0)
			(effects
				(font
					(size 1.27 1.27)
					(thickness 0.15)
				)
				(justify left bottom)
				(hide yes)
			)
		)
		(property "License" "Apache-2.0"
			(at 204.47 280.67 0)
			(effects
				(font
					(size 1.27 1.27)
					(thickness 0.15)
				)
				(justify left bottom)
				(hide yes)
			)
		)
		(pin "1"
		)
		(pin "2"
		)
		(pin "3"
		)
		(pin "4"
		)
		(pin "5"
		)
		(pin "6"
		)
		(instances
			(project "sdi-mipi-video-converter"
				(path ""
					(reference "U14")
					(unit 1)
				)
			)
		)
	)
	(symbol
		(lib_id "antmicroLEDIndicationDiscrete:LED_G_0603_LTST-C190GKT")
		(at 368.3 229.87 270)
		(mirror x)
		(unit 1)
		(exclude_from_sim no)
		(in_bom yes)
		(on_board yes)
		(dnp no)
		(property "Reference" "D12"
			(at 372.11 227.3301 90)
			(effects
				(font
					(size 1.27 1.27)
					(thickness 0.15)
				)
				(justify left)
			)
		)
		(property "Value" "LED_G_0603_LTST-C190GKT"
			(at 365.252 231.902 0)
			(effects
				(font
					(size 1.27 1.27)
					(thickness 0.15)
				)
				(justify left)
			)
		)
		(property "Footprint" "antmicro-footprints:LED_0603_1608Metric_G"
			(at 358.14 207.01 0)
			(effects
				(font
					(size 1.27 1.27)
					(thickness 0.15)
				)
				(justify left bottom)
				(hide yes)
			)
		)
		(property "Datasheet" "https://media.digikey.com/pdf/Data%20Sheets/Lite-On%20PDFs/LTST-C190GKT.pdf"
			(at 355.6 207.01 0)
			(effects
				(font
					(size 1.27 1.27)
					(thickness 0.15)
				)
				(justify left bottom)
				(hide yes)
			)
		)
		(property "Description" "LED, Green, SMD, 0603, 20 mA, 2.1 V, 569 nm"
			(at 368.3 229.87 0)
			(effects
				(font
					(size 1.27 1.27)
				)
				(hide yes)
			)
		)
		(property "MPN" "LTST-C190GKT"
			(at 353.06 207.01 0)
			(effects
				(font
					(size 1.27 1.27)
					(thickness 0.15)
				)
				(justify left bottom)
				(hide yes)
			)
		)
		(property "Manufacturer" "Lite-On"
			(at 350.52 207.01 0)
			(effects
				(font
					(size 1.27 1.27)
					(thickness 0.15)
				)
				(justify left bottom)
				(hide yes)
			)
		)
		(property "Author" "Antmicro"
			(at 347.98 207.01 0)
			(effects
				(font
					(size 1.27 1.27)
					(thickness 0.15)
				)
				(justify left bottom)
				(hide yes)
			)
		)
		(property "License" "Apache-2.0"
			(at 345.44 207.01 0)
			(effects
				(font
					(size 1.27 1.27)
					(thickness 0.15)
				)
				(justify left bottom)
				(hide yes)
			)
		)
		(property "Color" "Green"
			(at 363.22 207.01 0)
			(effects
				(font
					(size 1.27 1.27)
				)
				(justify left bottom)
				(hide yes)
			)
		)
		(pin "1"
		)
		(pin "2"
		)
		(instances
			(project "sdi-mipi-video-converter"
				(path ""
					(reference "D12")
					(unit 1)
				)
			)
		)
	)
	(symbol
		(lib_id "antmicropower:+3.3V")
		(at 148.59 209.55 0)
		(unit 1)
		(exclude_from_sim no)
		(in_bom yes)
		(on_board yes)
		(dnp no)
		(fields_autoplaced yes)
		(property "Reference" "#PWR0153"
			(at 148.59 213.36 0)
			(effects
				(font
					(size 1.27 1.27)
				)
				(hide yes)
			)
		)
		(property "Value" "+3V3"
			(at 148.59 204.47 0)
			(effects
				(font
					(size 1.27 1.27)
				)
			)
		)
		(property "Footprint" ""
			(at 148.59 209.55 0)
			(effects
				(font
					(size 1.27 1.27)
				)
				(hide yes)
			)
		)
		(property "Datasheet" ""
			(at 148.59 209.55 0)
			(effects
				(font
					(size 1.27 1.27)
				)
				(hide yes)
			)
		)
		(property "Description" ""
			(at 148.59 209.55 0)
			(effects
				(font
					(size 1.27 1.27)
				)
				(hide yes)
			)
		)
		(pin "1"
		)
		(instances
			(project "sdi-mipi-video-converter"
				(path ""
					(reference "#PWR0153")
					(unit 1)
				)
			)
		)
	)
	(symbol
		(lib_id "antmicroResistors0603:R_10k_0603")
		(at 96.52 269.24 270)
		(unit 1)
		(exclude_from_sim no)
		(in_bom yes)
		(on_board yes)
		(dnp no)
		(fields_autoplaced yes)
		(property "Reference" "R113"
			(at 99.06 270.5099 90)
			(effects
				(font
					(size 1.27 1.27)
					(thickness 0.15)
				)
				(justify left)
			)
		)
		(property "Value" "R_10k_0603"
			(at 83.82 289.56 0)
			(effects
				(font
					(size 1.27 1.27)
					(thickness 0.15)
				)
				(justify left bottom)
				(hide yes)
			)
		)
		(property "Footprint" "antmicro-footprints:R_0603_1608Metric"
			(at 81.28 289.56 0)
			(effects
				(font
					(size 1.27 1.27)
					(thickness 0.15)
				)
				(justify left bottom)
				(hide yes)
			)
		)
		(property "Datasheet" "https://www.bourns.com/docs/product-datasheets/cr.pdf"
			(at 78.74 289.56 0)
			(effects
				(font
					(size 1.27 1.27)
					(thickness 0.15)
				)
				(justify left bottom)
				(hide yes)
			)
		)
		(property "Description" "SMD Chip Resistor, 10 kohm, ± 1%, 100 mW, 0603 [1608 Metric], Thick Film, General Purpose"
			(at 96.52 269.24 0)
			(effects
				(font
					(size 1.27 1.27)
				)
				(hide yes)
			)
		)
		(property "Manufacturer" "Bourns"
			(at 73.66 289.56 0)
			(effects
				(font
					(size 1.27 1.27)
					(thickness 0.15)
				)
				(justify left bottom)
				(hide yes)
			)
		)
		(property "MPN" "CR0603-FX-1002ELF"
			(at 76.2 289.56 0)
			(effects
				(font
					(size 1.27 1.27)
					(thickness 0.15)
				)
				(justify left bottom)
				(hide yes)
			)
		)
		(property "Val" "10k"
			(at 99.06 273.0499 90)
			(effects
				(font
					(size 1.27 1.27)
					(thickness 0.15)
				)
				(justify left)
			)
		)
		(property "License" "Apache-2.0"
			(at 71.12 289.56 0)
			(effects
				(font
					(size 1.27 1.27)
					(thickness 0.15)
				)
				(justify left bottom)
				(hide yes)
			)
		)
		(property "Author" "Antmicro"
			(at 68.58 289.56 0)
			(effects
				(font
					(size 1.27 1.27)
					(thickness 0.15)
				)
				(justify left bottom)
				(hide yes)
			)
		)
		(property "Tolerance" "1%"
			(at 86.36 289.56 0)
			(effects
				(font
					(size 1.27 1.27)
				)
				(justify left bottom)
				(hide yes)
			)
		)
		(pin "1"
		)
		(pin "2"
		)
		(instances
			(project "sdi-mipi-video-converter"
				(path ""
					(reference "R113")
					(unit 1)
				)
			)
		)
	)
	(symbol
		(lib_id "antmicropower:GND")
		(at 278.13 237.49 0)
		(unit 1)
		(exclude_from_sim no)
		(in_bom yes)
		(on_board yes)
		(dnp no)
		(fields_autoplaced yes)
		(property "Reference" "#PWR0266"
			(at 287.02 240.03 0)
			(effects
				(font
					(size 1.27 1.27)
					(thickness 0.15)
				)
				(justify left bottom)
				(hide yes)
			)
		)
		(property "Value" "GND"
			(at 278.13 242.57 0)
			(effects
				(font
					(size 1.27 1.27)
					(thickness 0.15)
				)
			)
		)
		(property "Footprint" ""
			(at 287.02 245.11 0)
			(effects
				(font
					(size 1.27 1.27)
					(thickness 0.15)
				)
				(justify left bottom)
				(hide yes)
			)
		)
		(property "Datasheet" ""
			(at 287.02 250.19 0)
			(effects
				(font
					(size 1.27 1.27)
					(thickness 0.15)
				)
				(justify left bottom)
				(hide yes)
			)
		)
		(property "Description" ""
			(at 278.13 237.49 0)
			(effects
				(font
					(size 1.27 1.27)
				)
				(hide yes)
			)
		)
		(property "Author" "Antmicro"
			(at 287.02 245.11 0)
			(effects
				(font
					(size 1.27 1.27)
					(thickness 0.15)
				)
				(justify left bottom)
				(hide yes)
			)
		)
		(property "License" "Apache-2.0"
			(at 287.02 247.65 0)
			(effects
				(font
					(size 1.27 1.27)
					(thickness 0.15)
				)
				(justify left bottom)
				(hide yes)
			)
		)
		(pin "1"
		)
		(instances
			(project "sdi-mipi-video-converter"
				(path ""
					(reference "#PWR0266")
					(unit 1)
				)
			)
		)
	)
	(symbol
		(lib_id "antmicropower:GND")
		(at 306.07 157.48 0)
		(unit 1)
		(exclude_from_sim no)
		(in_bom yes)
		(on_board yes)
		(dnp no)
		(fields_autoplaced yes)
		(property "Reference" "#PWR0157"
			(at 314.96 160.02 0)
			(effects
				(font
					(size 1.27 1.27)
					(thickness 0.15)
				)
				(justify left bottom)
				(hide yes)
			)
		)
		(property "Value" "GND"
			(at 306.07 162.56 0)
			(effects
				(font
					(size 1.27 1.27)
					(thickness 0.15)
				)
			)
		)
		(property "Footprint" ""
			(at 314.96 165.1 0)
			(effects
				(font
					(size 1.27 1.27)
					(thickness 0.15)
				)
				(justify left bottom)
				(hide yes)
			)
		)
		(property "Datasheet" ""
			(at 314.96 170.18 0)
			(effects
				(font
					(size 1.27 1.27)
					(thickness 0.15)
				)
				(justify left bottom)
				(hide yes)
			)
		)
		(property "Description" ""
			(at 306.07 157.48 0)
			(effects
				(font
					(size 1.27 1.27)
				)
				(hide yes)
			)
		)
		(property "Author" "Antmicro"
			(at 314.96 165.1 0)
			(effects
				(font
					(size 1.27 1.27)
					(thickness 0.15)
				)
				(justify left bottom)
				(hide yes)
			)
		)
		(property "License" "Apache-2.0"
			(at 314.96 167.64 0)
			(effects
				(font
					(size 1.27 1.27)
					(thickness 0.15)
				)
				(justify left bottom)
				(hide yes)
			)
		)
		(pin "1"
		)
		(instances
			(project "sdi-mipi-video-converter"
				(path ""
					(reference "#PWR0157")
					(unit 1)
				)
			)
		)
	)
	(symbol
		(lib_id "antmicropower:GND")
		(at 40.64 213.36 0)
		(unit 1)
		(exclude_from_sim no)
		(in_bom yes)
		(on_board yes)
		(dnp no)
		(fields_autoplaced yes)
		(property "Reference" "#PWR012"
			(at 49.53 215.9 0)
			(effects
				(font
					(size 1.27 1.27)
					(thickness 0.15)
				)
				(justify left bottom)
				(hide yes)
			)
		)
		(property "Value" "GND"
			(at 40.64 218.44 0)
			(effects
				(font
					(size 1.27 1.27)
					(thickness 0.15)
				)
			)
		)
		(property "Footprint" ""
			(at 49.53 220.98 0)
			(effects
				(font
					(size 1.27 1.27)
					(thickness 0.15)
				)
				(justify left bottom)
				(hide yes)
			)
		)
		(property "Datasheet" ""
			(at 49.53 226.06 0)
			(effects
				(font
					(size 1.27 1.27)
					(thickness 0.15)
				)
				(justify left bottom)
				(hide yes)
			)
		)
		(property "Description" ""
			(at 40.64 213.36 0)
			(effects
				(font
					(size 1.27 1.27)
				)
				(hide yes)
			)
		)
		(property "Author" "Antmicro"
			(at 49.53 220.98 0)
			(effects
				(font
					(size 1.27 1.27)
					(thickness 0.15)
				)
				(justify left bottom)
				(hide yes)
			)
		)
		(property "License" "Apache-2.0"
			(at 49.53 223.52 0)
			(effects
				(font
					(size 1.27 1.27)
					(thickness 0.15)
				)
				(justify left bottom)
				(hide yes)
			)
		)
		(pin "1"
		)
		(instances
			(project "sdi-mipi-video-converter"
				(path ""
					(reference "#PWR012")
					(unit 1)
				)
			)
		)
	)
	(symbol
		(lib_id "antmicroResistors0603:R_200R_0603")
		(at 306.07 143.51 90)
		(unit 1)
		(exclude_from_sim no)
		(in_bom yes)
		(on_board yes)
		(dnp no)
		(fields_autoplaced yes)
		(property "Reference" "R111"
			(at 308.61 139.6999 90)
			(effects
				(font
					(size 1.27 1.27)
					(thickness 0.15)
				)
				(justify right)
			)
		)
		(property "Value" "R_200R_0603"
			(at 318.77 123.19 0)
			(effects
				(font
					(size 1.27 1.27)
					(thickness 0.15)
				)
				(justify left bottom)
				(hide yes)
			)
		)
		(property "Footprint" "antmicro-footprints:R_0603_1608Metric"
			(at 321.31 123.19 0)
			(effects
				(font
					(size 1.27 1.27)
					(thickness 0.15)
				)
				(justify left bottom)
				(hide yes)
			)
		)
		(property "Datasheet" "https://www.bourns.com/docs/product-datasheets/cr.pdf"
			(at 323.85 123.19 0)
			(effects
				(font
					(size 1.27 1.27)
					(thickness 0.15)
				)
				(justify left bottom)
				(hide yes)
			)
		)
		(property "Description" "SMD Chip Resistor, 200 ohm, ± 1%, 100 mW, 0603 [1608 Metric], Thick Film, General Purpose"
			(at 306.07 143.51 0)
			(effects
				(font
					(size 1.27 1.27)
				)
				(hide yes)
			)
		)
		(property "Manufacturer" "Bourns"
			(at 328.93 123.19 0)
			(effects
				(font
					(size 1.27 1.27)
					(thickness 0.15)
				)
				(justify left bottom)
				(hide yes)
			)
		)
		(property "MPN" "CR0603-FX-2000ELF"
			(at 326.39 123.19 0)
			(effects
				(font
					(size 1.27 1.27)
					(thickness 0.15)
				)
				(justify left bottom)
				(hide yes)
			)
		)
		(property "Val" "200R"
			(at 308.61 142.2399 90)
			(effects
				(font
					(size 1.27 1.27)
					(thickness 0.15)
				)
				(justify right)
			)
		)
		(property "License" "Apache-2.0"
			(at 331.47 123.19 0)
			(effects
				(font
					(size 1.27 1.27)
					(thickness 0.15)
				)
				(justify left bottom)
				(hide yes)
			)
		)
		(property "Author" "Antmicro"
			(at 334.01 123.19 0)
			(effects
				(font
					(size 1.27 1.27)
					(thickness 0.15)
				)
				(justify left bottom)
				(hide yes)
			)
		)
		(property "Tolerance" "1%"
			(at 316.23 123.19 0)
			(effects
				(font
					(size 1.27 1.27)
				)
				(justify left bottom)
				(hide yes)
			)
		)
		(pin "1"
		)
		(pin "2"
		)
		(instances
			(project "sdi-mipi-video-converter"
				(path ""
					(reference "R111")
					(unit 1)
				)
			)
		)
	)
	(symbol
		(lib_id "antmicroResistors0603:R_10k_0603")
		(at 168.91 269.24 90)
		(mirror x)
		(unit 1)
		(exclude_from_sim no)
		(in_bom no)
		(on_board yes)
		(dnp yes)
		(property "Reference" "R106"
			(at 167.64 270.51 90)
			(effects
				(font
					(size 1.27 1.27)
					(thickness 0.15)
				)
				(justify left)
			)
		)
		(property "Value" "R_10k_0603"
			(at 181.61 289.56 0)
			(effects
				(font
					(size 1.27 1.27)
					(thickness 0.15)
				)
				(justify left bottom)
				(hide yes)
			)
		)
		(property "Footprint" "antmicro-footprints:R_0603_1608Metric"
			(at 184.15 289.56 0)
			(effects
				(font
					(size 1.27 1.27)
					(thickness 0.15)
				)
				(justify left bottom)
				(hide yes)
			)
		)
		(property "Datasheet" "https://www.bourns.com/docs/product-datasheets/cr.pdf"
			(at 186.69 289.56 0)
			(effects
				(font
					(size 1.27 1.27)
					(thickness 0.15)
				)
				(justify left bottom)
				(hide yes)
			)
		)
		(property "Description" "SMD Chip Resistor, 10 kohm, ± 1%, 100 mW, 0603 [1608 Metric], Thick Film, General Purpose"
			(at 168.91 269.24 0)
			(effects
				(font
					(size 1.27 1.27)
				)
				(hide yes)
			)
		)
		(property "Manufacturer" "Bourns"
			(at 191.77 289.56 0)
			(effects
				(font
					(size 1.27 1.27)
					(thickness 0.15)
				)
				(justify left bottom)
				(hide yes)
			)
		)
		(property "MPN" "CR0603-FX-1002ELF"
			(at 189.23 289.56 0)
			(effects
				(font
					(size 1.27 1.27)
					(thickness 0.15)
				)
				(justify left bottom)
				(hide yes)
			)
		)
		(property "Val" "10k"
			(at 167.64 273.05 90)
			(effects
				(font
					(size 1.27 1.27)
					(thickness 0.15)
				)
				(justify left)
			)
		)
		(property "License" "Apache-2.0"
			(at 194.31 289.56 0)
			(effects
				(font
					(size 1.27 1.27)
					(thickness 0.15)
				)
				(justify left bottom)
				(hide yes)
			)
		)
		(property "Author" "Antmicro"
			(at 196.85 289.56 0)
			(effects
				(font
					(size 1.27 1.27)
					(thickness 0.15)
				)
				(justify left bottom)
				(hide yes)
			)
		)
		(property "Tolerance" "1%"
			(at 179.07 289.56 0)
			(effects
				(font
					(size 1.27 1.27)
				)
				(justify left bottom)
				(hide yes)
			)
		)
		(pin "1"
		)
		(pin "2"
		)
		(instances
			(project "sdi-mipi-video-converter"
				(path ""
					(reference "R106")
					(unit 1)
				)
			)
		)
	)
	(symbol
		(lib_id "antmicroTestPoints:TP_0.75mm_SMD")
		(at 340.36 237.49 0)
		(unit 1)
		(exclude_from_sim no)
		(in_bom yes)
		(on_board yes)
		(dnp no)
		(fields_autoplaced yes)
		(property "Reference" "TP47"
			(at 345.44 237.4899 0)
			(effects
				(font
					(size 1.27 1.27)
					(thickness 0.15)
				)
				(justify left)
			)
		)
		(property "Value" "TP_0.75mm_SMD"
			(at 358.14 245.11 0)
			(effects
				(font
					(size 1.27 1.27)
					(thickness 0.15)
				)
				(justify left bottom)
				(hide yes)
			)
		)
		(property "Footprint" "antmicro-footprints:TP_SMD_0.75mm"
			(at 358.14 247.65 0)
			(effects
				(font
					(size 1.27 1.27)
					(thickness 0.15)
				)
				(justify left bottom)
				(hide yes)
			)
		)
		(property "Datasheet" ""
			(at 358.14 250.19 0)
			(effects
				(font
					(size 1.27 1.27)
					(thickness 0.15)
				)
				(justify left bottom)
				(hide yes)
			)
		)
		(property "Description" "SMT test point"
			(at 340.36 237.49 0)
			(effects
				(font
					(size 1.27 1.27)
				)
				(hide yes)
			)
		)
		(property "MPN" ""
			(at 358.14 252.73 0)
			(effects
				(font
					(size 1.27 1.27)
					(thickness 0.15)
				)
				(justify left bottom)
				(hide yes)
			)
		)
		(property "Manufacturer" ""
			(at 358.14 255.27 0)
			(effects
				(font
					(size 1.27 1.27)
					(thickness 0.15)
				)
				(justify left bottom)
				(hide yes)
			)
		)
		(property "Author" "Antmicro"
			(at 358.14 257.81 0)
			(effects
				(font
					(size 1.27 1.27)
					(thickness 0.15)
				)
				(justify left bottom)
				(hide yes)
			)
		)
		(property "License" "Apache-2.0"
			(at 358.14 260.35 0)
			(effects
				(font
					(size 1.27 1.27)
					(thickness 0.15)
				)
				(justify left bottom)
				(hide yes)
			)
		)
		(pin "1"
		)
		(instances
			(project "sdi-mipi-video-converter"
				(path ""
					(reference "TP47")
					(unit 1)
				)
			)
		)
	)
	(symbol
		(lib_id "antmicroCapacitors0402:C_100n_0402")
		(at 308.61 241.3 90)
		(unit 1)
		(exclude_from_sim no)
		(in_bom yes)
		(on_board yes)
		(dnp no)
		(fields_autoplaced yes)
		(property "Reference" "C123"
			(at 306.07 237.4835 90)
			(effects
				(font
					(size 1.27 1.27)
					(thickness 0.15)
				)
				(justify left)
			)
		)
		(property "Value" "C_100n_0402"
			(at 318.77 220.98 0)
			(effects
				(font
					(size 1.27 1.27)
					(thickness 0.15)
				)
				(justify left bottom)
				(hide yes)
			)
		)
		(property "Footprint" "antmicro-footprints:C_0402_1005Metric"
			(at 321.31 220.98 0)
			(effects
				(font
					(size 1.27 1.27)
					(thickness 0.15)
				)
				(justify left bottom)
				(hide yes)
			)
		)
		(property "Datasheet" "https://www.murata.com/products/productdetail?partno=GRM155R61H104KE14%23"
			(at 323.85 220.98 0)
			(effects
				(font
					(size 1.27 1.27)
					(thickness 0.15)
				)
				(justify left bottom)
				(hide yes)
			)
		)
		(property "Description" "SMD Multilayer Ceramic Capacitor, 0.1 µF, 50 V, 0402 [1005 Metric], ± 10%, X5R, GRM Series"
			(at 308.61 241.3 0)
			(effects
				(font
					(size 1.27 1.27)
				)
				(hide yes)
			)
		)
		(property "Manufacturer" "Murata"
			(at 328.93 220.98 0)
			(effects
				(font
					(size 1.27 1.27)
					(thickness 0.15)
				)
				(justify left bottom)
				(hide yes)
			)
		)
		(property "MPN" "GRM155R61H104KE14D"
			(at 326.39 220.98 0)
			(effects
				(font
					(size 1.27 1.27)
					(thickness 0.15)
				)
				(justify left bottom)
				(hide yes)
			)
		)
		(property "Val" "100n"
			(at 306.07 240.0235 90)
			(effects
				(font
					(size 1.27 1.27)
					(thickness 0.15)
				)
				(justify left)
			)
		)
		(property "License" "Apache-2.0"
			(at 331.47 220.98 0)
			(effects
				(font
					(size 1.27 1.27)
					(thickness 0.15)
				)
				(justify left bottom)
				(hide yes)
			)
		)
		(property "Author" "Antmicro"
			(at 334.01 220.98 0)
			(effects
				(font
					(size 1.27 1.27)
					(thickness 0.15)
				)
				(justify left bottom)
				(hide yes)
			)
		)
		(property "Voltage" "50V"
			(at 336.55 220.98 0)
			(effects
				(font
					(size 1.27 1.27)
				)
				(justify left bottom)
				(hide yes)
			)
		)
		(property "Dielectric" "X5R"
			(at 339.09 220.98 0)
			(effects
				(font
					(size 1.27 1.27)
				)
				(justify left bottom)
				(hide yes)
			)
		)
		(pin "1"
		)
		(pin "2"
		)
		(instances
			(project "sdi-mipi-video-converter"
				(path ""
					(reference "C123")
					(unit 1)
				)
			)
		)
	)
	(symbol
		(lib_id "antmicroCapacitorsmisc:C_100n_0201")
		(at 114.3 135.89 90)
		(unit 1)
		(exclude_from_sim no)
		(in_bom yes)
		(on_board yes)
		(dnp no)
		(fields_autoplaced yes)
		(property "Reference" "C84"
			(at 116.84 132.0735 90)
			(effects
				(font
					(size 1.27 1.27)
					(thickness 0.15)
				)
				(justify right)
			)
		)
		(property "Value" "C_100n_0201"
			(at 124.46 115.57 0)
			(effects
				(font
					(size 1.27 1.27)
					(thickness 0.15)
				)
				(justify left bottom)
				(hide yes)
			)
		)
		(property "Footprint" "antmicro-footprints:C_0201"
			(at 127 115.57 0)
			(effects
				(font
					(size 1.27 1.27)
					(thickness 0.15)
				)
				(justify left bottom)
				(hide yes)
			)
		)
		(property "Datasheet" "https://www.yageo.com/en/Chart/Download/pdf/CC0201KRX6S5BB104"
			(at 129.54 115.57 0)
			(effects
				(font
					(size 1.27 1.27)
					(thickness 0.15)
				)
				(justify left bottom)
				(hide yes)
			)
		)
		(property "Description" "SMD Multilayer Ceramic Capacitor, 0.1 µF, 6.3 V, 0201 [0603 Metric], ± 10%, X6S, CC Series"
			(at 114.3 135.89 0)
			(effects
				(font
					(size 1.27 1.27)
				)
				(hide yes)
			)
		)
		(property "Manufacturer" "YAGEO"
			(at 134.62 115.57 0)
			(effects
				(font
					(size 1.27 1.27)
					(thickness 0.15)
				)
				(justify left bottom)
				(hide yes)
			)
		)
		(property "MPN" "CC0201KRX6S5BB104"
			(at 132.08 115.57 0)
			(effects
				(font
					(size 1.27 1.27)
					(thickness 0.15)
				)
				(justify left bottom)
				(hide yes)
			)
		)
		(property "Val" "100n"
			(at 116.84 134.6135 90)
			(effects
				(font
					(size 1.27 1.27)
					(thickness 0.15)
				)
				(justify right)
			)
		)
		(property "License" "Apache-2.0"
			(at 137.16 115.57 0)
			(effects
				(font
					(size 1.27 1.27)
					(thickness 0.15)
				)
				(justify left bottom)
				(hide yes)
			)
		)
		(property "Author" "Antmicro"
			(at 139.7 115.57 0)
			(effects
				(font
					(size 1.27 1.27)
					(thickness 0.15)
				)
				(justify left bottom)
				(hide yes)
			)
		)
		(property "Voltage" ""
			(at 142.24 115.57 0)
			(effects
				(font
					(size 1.27 1.27)
				)
				(justify left bottom)
				(hide yes)
			)
		)
		(property "Dielectric" ""
			(at 144.78 115.57 0)
			(effects
				(font
					(size 1.27 1.27)
				)
				(justify left bottom)
				(hide yes)
			)
		)
		(property "Public" "False"
			(at 147.32 115.57 0)
			(effects
				(font
					(size 1.27 1.27)
				)
				(justify left bottom)
				(hide yes)
			)
		)
		(pin "1"
		)
		(pin "2"
		)
		(instances
			(project "sdi-mipi-video-converter"
				(path ""
					(reference "C84")
					(unit 1)
				)
			)
		)
	)
	(symbol
		(lib_id "antmicropower:+3.3V")
		(at 96.52 267.97 0)
		(unit 1)
		(exclude_from_sim no)
		(in_bom yes)
		(on_board yes)
		(dnp no)
		(fields_autoplaced yes)
		(property "Reference" "#PWR09"
			(at 96.52 271.78 0)
			(effects
				(font
					(size 1.27 1.27)
				)
				(hide yes)
			)
		)
		(property "Value" "+3V3"
			(at 96.52 262.89 0)
			(effects
				(font
					(size 1.27 1.27)
				)
			)
		)
		(property "Footprint" ""
			(at 96.52 267.97 0)
			(effects
				(font
					(size 1.27 1.27)
				)
				(hide yes)
			)
		)
		(property "Datasheet" ""
			(at 96.52 267.97 0)
			(effects
				(font
					(size 1.27 1.27)
				)
				(hide yes)
			)
		)
		(property "Description" ""
			(at 96.52 267.97 0)
			(effects
				(font
					(size 1.27 1.27)
				)
				(hide yes)
			)
		)
		(pin "1"
		)
		(instances
			(project "sdi-mipi-video-converter"
				(path ""
					(reference "#PWR09")
					(unit 1)
				)
			)
		)
	)
	(symbol
		(lib_id "antmicropower:GND")
		(at 199.39 234.95 0)
		(unit 1)
		(exclude_from_sim no)
		(in_bom yes)
		(on_board yes)
		(dnp no)
		(fields_autoplaced yes)
		(property "Reference" "#PWR0254"
			(at 208.28 237.49 0)
			(effects
				(font
					(size 1.27 1.27)
					(thickness 0.15)
				)
				(justify left bottom)
				(hide yes)
			)
		)
		(property "Value" "GND"
			(at 199.39 240.03 0)
			(effects
				(font
					(size 1.27 1.27)
					(thickness 0.15)
				)
			)
		)
		(property "Footprint" ""
			(at 208.28 242.57 0)
			(effects
				(font
					(size 1.27 1.27)
					(thickness 0.15)
				)
				(justify left bottom)
				(hide yes)
			)
		)
		(property "Datasheet" ""
			(at 208.28 247.65 0)
			(effects
				(font
					(size 1.27 1.27)
					(thickness 0.15)
				)
				(justify left bottom)
				(hide yes)
			)
		)
		(property "Description" ""
			(at 199.39 234.95 0)
			(effects
				(font
					(size 1.27 1.27)
				)
				(hide yes)
			)
		)
		(property "Author" "Antmicro"
			(at 208.28 242.57 0)
			(effects
				(font
					(size 1.27 1.27)
					(thickness 0.15)
				)
				(justify left bottom)
				(hide yes)
			)
		)
		(property "License" "Apache-2.0"
			(at 208.28 245.11 0)
			(effects
				(font
					(size 1.27 1.27)
					(thickness 0.15)
				)
				(justify left bottom)
				(hide yes)
			)
		)
		(pin "1"
		)
		(instances
			(project "sdi-mipi-video-converter"
				(path ""
					(reference "#PWR0254")
					(unit 1)
				)
			)
		)
	)
	(symbol
		(lib_id "antmicroWire2BoardConnectors:JST_SH_1x4_SM04B-SRSS-TB-LF-SN")
		(at 44.45 200.66 0)
		(unit 1)
		(exclude_from_sim no)
		(in_bom yes)
		(on_board yes)
		(dnp no)
		(property "Reference" "J8"
			(at 52.705 204.47 0)
			(effects
				(font
					(size 1.27 1.27)
					(thickness 0.15)
				)
				(justify left)
			)
		)
		(property "Value" "SM04B-SRSS-TB-LF-SN"
			(at 52.705 207.01 0)
			(effects
				(font
					(size 1.27 1.27)
					(thickness 0.15)
				)
				(justify left)
				(hide yes)
			)
		)
		(property "Footprint" "antmicro-footprints:Conn_JST_SH_1x4_SM04B-SRSS-TB-LF-SN"
			(at 71.12 210.82 0)
			(effects
				(font
					(size 1.27 1.27)
					(thickness 0.15)
				)
				(justify left bottom)
				(hide yes)
			)
		)
		(property "Datasheet" "https://www.jst-mfg.com/product/pdf/eng/eSH.pdf"
			(at 71.12 213.36 0)
			(effects
				(font
					(size 1.27 1.27)
					(thickness 0.15)
				)
				(justify left bottom)
				(hide yes)
			)
		)
		(property "Description" "Pin Header, Right Angle, Wire-to-Board, 1 mm, 1 Rows, 4 Contacts, Surface Mount Right Angle, SH"
			(at 44.45 200.66 0)
			(effects
				(font
					(size 1.27 1.27)
				)
				(hide yes)
			)
		)
		(property "MPN" "SM04B-SRSS-TB(LF)(SN)"
			(at 52.705 207.01 0)
			(effects
				(font
					(size 1.27 1.27)
					(thickness 0.15)
				)
				(justify left)
			)
		)
		(property "Manufacturer" "JST Automotive Connectors"
			(at 71.12 215.9 0)
			(effects
				(font
					(size 1.27 1.27)
					(thickness 0.15)
				)
				(justify left bottom)
				(hide yes)
			)
		)
		(property "Author" "Antmicro"
			(at 71.12 218.44 0)
			(effects
				(font
					(size 1.27 1.27)
					(thickness 0.15)
				)
				(justify left bottom)
				(hide yes)
			)
		)
		(property "License" "Apache-2.0"
			(at 71.12 220.98 0)
			(effects
				(font
					(size 1.27 1.27)
					(thickness 0.15)
				)
				(justify left bottom)
				(hide yes)
			)
		)
		(pin "1"
		)
		(pin "2"
		)
		(pin "3"
		)
		(pin "4"
		)
		(pin "MP"
		)
		(instances
			(project "sdi-mipi-video-converter"
				(path ""
					(reference "J8")
					(unit 1)
				)
			)
		)
	)
	(symbol
		(lib_id "antmicropower:GND")
		(at 267.97 237.49 0)
		(unit 1)
		(exclude_from_sim no)
		(in_bom yes)
		(on_board yes)
		(dnp no)
		(fields_autoplaced yes)
		(property "Reference" "#PWR0265"
			(at 276.86 240.03 0)
			(effects
				(font
					(size 1.27 1.27)
					(thickness 0.15)
				)
				(justify left bottom)
				(hide yes)
			)
		)
		(property "Value" "GND"
			(at 267.97 242.57 0)
			(effects
				(font
					(size 1.27 1.27)
					(thickness 0.15)
				)
			)
		)
		(property "Footprint" ""
			(at 276.86 245.11 0)
			(effects
				(font
					(size 1.27 1.27)
					(thickness 0.15)
				)
				(justify left bottom)
				(hide yes)
			)
		)
		(property "Datasheet" ""
			(at 276.86 250.19 0)
			(effects
				(font
					(size 1.27 1.27)
					(thickness 0.15)
				)
				(justify left bottom)
				(hide yes)
			)
		)
		(property "Description" ""
			(at 267.97 237.49 0)
			(effects
				(font
					(size 1.27 1.27)
				)
				(hide yes)
			)
		)
		(property "Author" "Antmicro"
			(at 276.86 245.11 0)
			(effects
				(font
					(size 1.27 1.27)
					(thickness 0.15)
				)
				(justify left bottom)
				(hide yes)
			)
		)
		(property "License" "Apache-2.0"
			(at 276.86 247.65 0)
			(effects
				(font
					(size 1.27 1.27)
					(thickness 0.15)
				)
				(justify left bottom)
				(hide yes)
			)
		)
		(pin "1"
		)
		(instances
			(project "sdi-mipi-video-converter"
				(path ""
					(reference "#PWR0265")
					(unit 1)
				)
			)
		)
	)
	(symbol
		(lib_id "antmicropower:GND")
		(at 119.38 243.84 0)
		(unit 1)
		(exclude_from_sim no)
		(in_bom yes)
		(on_board yes)
		(dnp no)
		(fields_autoplaced yes)
		(property "Reference" "#PWR014"
			(at 128.27 246.38 0)
			(effects
				(font
					(size 1.27 1.27)
					(thickness 0.15)
				)
				(justify left bottom)
				(hide yes)
			)
		)
		(property "Value" "GND"
			(at 119.38 248.92 0)
			(effects
				(font
					(size 1.27 1.27)
					(thickness 0.15)
				)
			)
		)
		(property "Footprint" ""
			(at 128.27 251.46 0)
			(effects
				(font
					(size 1.27 1.27)
					(thickness 0.15)
				)
				(justify left bottom)
				(hide yes)
			)
		)
		(property "Datasheet" ""
			(at 128.27 256.54 0)
			(effects
				(font
					(size 1.27 1.27)
					(thickness 0.15)
				)
				(justify left bottom)
				(hide yes)
			)
		)
		(property "Description" ""
			(at 119.38 243.84 0)
			(effects
				(font
					(size 1.27 1.27)
				)
				(hide yes)
			)
		)
		(property "Author" "Antmicro"
			(at 128.27 251.46 0)
			(effects
				(font
					(size 1.27 1.27)
					(thickness 0.15)
				)
				(justify left bottom)
				(hide yes)
			)
		)
		(property "License" "Apache-2.0"
			(at 128.27 254 0)
			(effects
				(font
					(size 1.27 1.27)
					(thickness 0.15)
				)
				(justify left bottom)
				(hide yes)
			)
		)
		(pin "1"
		)
		(instances
			(project "sdi-mipi-video-converter"
				(path ""
					(reference "#PWR014")
					(unit 1)
				)
			)
		)
	)
	(symbol
		(lib_id "antmicroLEDIndicationDiscrete:LED_G_0603_LTST-C190GKT")
		(at 87.63 213.36 270)
		(mirror x)
		(unit 1)
		(exclude_from_sim no)
		(in_bom yes)
		(on_board yes)
		(dnp no)
		(fields_autoplaced yes)
		(property "Reference" "D11"
			(at 91.44 209.55 90)
			(effects
				(font
					(size 1.27 1.27)
					(thickness 0.15)
				)
				(justify left)
			)
		)
		(property "Value" "LED_G_0603_LTST-C190GKT"
			(at 91.44 212.09 90)
			(effects
				(font
					(size 1.27 1.27)
					(thickness 0.15)
				)
				(justify left)
			)
		)
		(property "Footprint" "antmicro-footprints:LED_0603_1608Metric_G"
			(at 77.47 190.5 0)
			(effects
				(font
					(size 1.27 1.27)
					(thickness 0.15)
				)
				(justify left bottom)
				(hide yes)
			)
		)
		(property "Datasheet" "https://media.digikey.com/pdf/Data%20Sheets/Lite-On%20PDFs/LTST-C190GKT.pdf"
			(at 74.93 190.5 0)
			(effects
				(font
					(size 1.27 1.27)
					(thickness 0.15)
				)
				(justify left bottom)
				(hide yes)
			)
		)
		(property "Description" "LED, Green, SMD, 0603, 20 mA, 2.1 V, 569 nm"
			(at 87.63 213.36 0)
			(effects
				(font
					(size 1.27 1.27)
				)
				(hide yes)
			)
		)
		(property "MPN" "LTST-C190GKT"
			(at 72.39 190.5 0)
			(effects
				(font
					(size 1.27 1.27)
					(thickness 0.15)
				)
				(justify left bottom)
				(hide yes)
			)
		)
		(property "Manufacturer" "Lite-On"
			(at 69.85 190.5 0)
			(effects
				(font
					(size 1.27 1.27)
					(thickness 0.15)
				)
				(justify left bottom)
				(hide yes)
			)
		)
		(property "Author" "Antmicro"
			(at 67.31 190.5 0)
			(effects
				(font
					(size 1.27 1.27)
					(thickness 0.15)
				)
				(justify left bottom)
				(hide yes)
			)
		)
		(property "License" "Apache-2.0"
			(at 64.77 190.5 0)
			(effects
				(font
					(size 1.27 1.27)
					(thickness 0.15)
				)
				(justify left bottom)
				(hide yes)
			)
		)
		(property "Color" "Green"
			(at 91.44 213.3599 90)
			(effects
				(font
					(size 1.27 1.27)
				)
				(justify left)
				(hide yes)
			)
		)
		(pin "1"
		)
		(pin "2"
		)
		(instances
			(project "sdi-mipi-video-converter"
				(path ""
					(reference "D11")
					(unit 1)
				)
			)
		)
	)
	(symbol
		(lib_id "antmicroCapacitors0603:C_1u_0603")
		(at 119.38 240.03 90)
		(unit 1)
		(exclude_from_sim no)
		(in_bom yes)
		(on_board yes)
		(dnp no)
		(fields_autoplaced yes)
		(property "Reference" "C114"
			(at 121.92 236.2135 90)
			(effects
				(font
					(size 1.27 1.27)
					(thickness 0.15)
				)
				(justify right)
			)
		)
		(property "Value" "C_1u_0603"
			(at 129.54 219.71 0)
			(effects
				(font
					(size 1.27 1.27)
					(thickness 0.15)
				)
				(justify left bottom)
				(hide yes)
			)
		)
		(property "Footprint" "antmicro-footprints:C_0603_1608Metric"
			(at 132.08 219.71 0)
			(effects
				(font
					(size 1.27 1.27)
					(thickness 0.15)
				)
				(justify left bottom)
				(hide yes)
			)
		)
		(property "Datasheet" "https://spicat.kyocera-avx.com/product/mlcc/chartview/0603YD105KAT2A/"
			(at 134.62 219.71 0)
			(effects
				(font
					(size 1.27 1.27)
					(thickness 0.15)
				)
				(justify left bottom)
				(hide yes)
			)
		)
		(property "Description" "SMD Multilayer Ceramic Capacitor, 1 µF, 16 V, 0603 [1608 Metric], ± 10%, X5R, AVX 0603 MLCC"
			(at 119.38 240.03 0)
			(effects
				(font
					(size 1.27 1.27)
				)
				(hide yes)
			)
		)
		(property "Manufacturer" "KYOCERA AVX"
			(at 139.7 219.71 0)
			(effects
				(font
					(size 1.27 1.27)
					(thickness 0.15)
				)
				(justify left bottom)
				(hide yes)
			)
		)
		(property "MPN" "0603YD105KAT2A"
			(at 137.16 219.71 0)
			(effects
				(font
					(size 1.27 1.27)
					(thickness 0.15)
				)
				(justify left bottom)
				(hide yes)
			)
		)
		(property "Val" "1u"
			(at 121.92 238.7535 90)
			(effects
				(font
					(size 1.27 1.27)
					(thickness 0.15)
				)
				(justify right)
			)
		)
		(property "License" "Apache-2.0"
			(at 142.24 219.71 0)
			(effects
				(font
					(size 1.27 1.27)
					(thickness 0.15)
				)
				(justify left bottom)
				(hide yes)
			)
		)
		(property "Author" "Antmicro"
			(at 144.78 219.71 0)
			(effects
				(font
					(size 1.27 1.27)
					(thickness 0.15)
				)
				(justify left bottom)
				(hide yes)
			)
		)
		(property "Voltage" ""
			(at 147.32 219.71 0)
			(effects
				(font
					(size 1.27 1.27)
				)
				(justify left bottom)
				(hide yes)
			)
		)
		(property "Dielectric" ""
			(at 149.86 219.71 0)
			(effects
				(font
					(size 1.27 1.27)
				)
				(justify left bottom)
				(hide yes)
			)
		)
		(pin "1"
		)
		(pin "2"
		)
		(instances
			(project "sdi-mipi-video-converter"
				(path ""
					(reference "C114")
					(unit 1)
				)
			)
		)
	)
	(symbol
		(lib_id "antmicroResistors0603:R_10k_0603")
		(at 157.48 217.17 270)
		(unit 1)
		(exclude_from_sim no)
		(in_bom yes)
		(on_board yes)
		(dnp no)
		(property "Reference" "R104"
			(at 158.75 218.44 90)
			(effects
				(font
					(size 1.27 1.27)
					(thickness 0.15)
				)
				(justify left)
			)
		)
		(property "Value" "R_10k_0603"
			(at 144.78 237.49 0)
			(effects
				(font
					(size 1.27 1.27)
					(thickness 0.15)
				)
				(justify left bottom)
				(hide yes)
			)
		)
		(property "Footprint" "antmicro-footprints:R_0603_1608Metric"
			(at 142.24 237.49 0)
			(effects
				(font
					(size 1.27 1.27)
					(thickness 0.15)
				)
				(justify left bottom)
				(hide yes)
			)
		)
		(property "Datasheet" "https://www.bourns.com/docs/product-datasheets/cr.pdf"
			(at 139.7 237.49 0)
			(effects
				(font
					(size 1.27 1.27)
					(thickness 0.15)
				)
				(justify left bottom)
				(hide yes)
			)
		)
		(property "Description" "SMD Chip Resistor, 10 kohm, ± 1%, 100 mW, 0603 [1608 Metric], Thick Film, General Purpose"
			(at 157.48 217.17 0)
			(effects
				(font
					(size 1.27 1.27)
				)
				(hide yes)
			)
		)
		(property "Manufacturer" "Bourns"
			(at 134.62 237.49 0)
			(effects
				(font
					(size 1.27 1.27)
					(thickness 0.15)
				)
				(justify left bottom)
				(hide yes)
			)
		)
		(property "MPN" "CR0603-FX-1002ELF"
			(at 137.16 237.49 0)
			(effects
				(font
					(size 1.27 1.27)
					(thickness 0.15)
				)
				(justify left bottom)
				(hide yes)
			)
		)
		(property "Val" "10k"
			(at 158.75 220.98 90)
			(effects
				(font
					(size 1.27 1.27)
					(thickness 0.15)
				)
				(justify left)
			)
		)
		(property "License" "Apache-2.0"
			(at 132.08 237.49 0)
			(effects
				(font
					(size 1.27 1.27)
					(thickness 0.15)
				)
				(justify left bottom)
				(hide yes)
			)
		)
		(property "Author" "Antmicro"
			(at 129.54 237.49 0)
			(effects
				(font
					(size 1.27 1.27)
					(thickness 0.15)
				)
				(justify left bottom)
				(hide yes)
			)
		)
		(property "Tolerance" "1%"
			(at 147.32 237.49 0)
			(effects
				(font
					(size 1.27 1.27)
				)
				(justify left bottom)
				(hide yes)
			)
		)
		(pin "1"
		)
		(pin "2"
		)
		(instances
			(project "sdi-mipi-video-converter"
				(path ""
					(reference "R104")
					(unit 1)
				)
			)
		)
	)
	(symbol
		(lib_id "antmicroFPGAChips:CrossLink_LIFCL-40-9BG256C")
		(at 50.8 33.02 0)
		(mirror y)
		(unit 9)
		(exclude_from_sim no)
		(in_bom yes)
		(on_board yes)
		(dnp no)
		(fields_autoplaced yes)
		(property "Reference" "U11"
			(at 36.195 25.4 0)
			(effects
				(font
					(size 1.27 1.27)
					(thickness 0.15)
				)
			)
		)
		(property "Value" "LIFCL-40-9BG256C"
			(at -2.54 38.1 0)
			(effects
				(font
					(size 1.27 1.27)
					(thickness 0.15)
				)
				(justify left bottom)
				(hide yes)
			)
		)
		(property "Footprint" "antmicro-footprints:BGA-256_14x14mm_Layout16x16_P0.8mm"
			(at -2.54 40.64 0)
			(effects
				(font
					(size 1.27 1.27)
					(thickness 0.15)
				)
				(justify left bottom)
				(hide yes)
			)
		)
		(property "Datasheet" "https://www.latticesemi.com/-/media/LatticeSemi/Documents/DataSheets/CrossLink/FPGA-DS-02007-2-1-CrossLink-Family-Data-Sheet.ashx?document_id=51662"
			(at -2.54 43.18 0)
			(effects
				(font
					(size 1.27 1.27)
					(thickness 0.15)
				)
				(justify left bottom)
				(hide yes)
			)
		)
		(property "Description" "CrossLink-NX™ Field Programmable Gate Array 256-LFBGA"
			(at 50.8 33.02 0)
			(effects
				(font
					(size 1.27 1.27)
				)
				(hide yes)
			)
		)
		(property "MPN" "LIFCL-40-9BG256C"
			(at 36.195 27.94 0)
			(effects
				(font
					(size 1.27 1.27)
					(thickness 0.15)
				)
			)
		)
		(property "Manufacturer" "Lattice Semiconductor"
			(at -2.54 45.72 0)
			(effects
				(font
					(size 1.27 1.27)
					(thickness 0.15)
				)
				(justify left bottom)
				(hide yes)
			)
		)
		(property "Author" "Antmicro"
			(at -2.54 48.26 0)
			(effects
				(font
					(size 1.27 1.27)
					(thickness 0.15)
				)
				(justify left bottom)
				(hide yes)
			)
		)
		(property "License" "Apache-2.0"
			(at -2.54 50.8 0)
			(effects
				(font
					(size 1.27 1.27)
					(thickness 0.15)
				)
				(justify left bottom)
				(hide yes)
			)
		)
		(pin "B16"
		)
		(pin "C12"
		)
		(pin "C13"
		)
		(pin "C14"
		)
		(pin "C15"
		)
		(pin "C16"
		)
		(pin "D11"
		)
		(pin "D12"
		)
		(pin "D13"
		)
		(pin "D15"
		)
		(pin "D16"
		)
		(pin "E15"
		)
		(pin "E16"
		)
		(pin "D10"
		)
		(pin "E10"
		)
		(pin "E11"
		)
		(pin "E12"
		)
		(pin "E13"
		)
		(pin "E14"
		)
		(pin "E9"
		)
		(pin "F10"
		)
		(pin "F11"
		)
		(pin "F13"
		)
		(pin "F14"
		)
		(pin "F15"
		)
		(pin "F16"
		)
		(pin "F9"
		)
		(pin "G10"
		)
		(pin "G11"
		)
		(pin "G12"
		)
		(pin "G13"
		)
		(pin "G14"
		)
		(pin "G15"
		)
		(pin "G16"
		)
		(pin "G9"
		)
		(pin "H10"
		)
		(pin "H11"
		)
		(pin "H12"
		)
		(pin "H13"
		)
		(pin "H14"
		)
		(pin "H15"
		)
		(pin "H16"
		)
		(pin "J11"
		)
		(pin "J12"
		)
		(pin "J13"
		)
		(pin "J15"
		)
		(pin "J16"
		)
		(pin "K11"
		)
		(pin "K12"
		)
		(pin "L10"
		)
		(pin "L11"
		)
		(pin "L12"
		)
		(pin "M11"
		)
		(pin "M12"
		)
		(pin "M13"
		)
		(pin "M14"
		)
		(pin "M15"
		)
		(pin "M16"
		)
		(pin "N11"
		)
		(pin "N12"
		)
		(pin "N13"
		)
		(pin "N14"
		)
		(pin "N15"
		)
		(pin "N16"
		)
		(pin "P10"
		)
		(pin "P11"
		)
		(pin "P12"
		)
		(pin "P14"
		)
		(pin "P15"
		)
		(pin "P16"
		)
		(pin "R10"
		)
		(pin "R11"
		)
		(pin "R12"
		)
		(pin "R13"
		)
		(pin "R14"
		)
		(pin "R15"
		)
		(pin "R16"
		)
		(pin "T11"
		)
		(pin "T12"
		)
		(pin "T13"
		)
		(pin "T14"
		)
		(pin "T15"
		)
		(pin "L8"
		)
		(pin "L9"
		)
		(pin "M10"
		)
		(pin "M8"
		)
		(pin "M9"
		)
		(pin "N10"
		)
		(pin "N6"
		)
		(pin "N8"
		)
		(pin "N9"
		)
		(pin "P4"
		)
		(pin "P5"
		)
		(pin "P6"
		)
		(pin "P7"
		)
		(pin "P8"
		)
		(pin "P9"
		)
		(pin "R1"
		)
		(pin "R2"
		)
		(pin "R3"
		)
		(pin "R4"
		)
		(pin "R5"
		)
		(pin "R6"
		)
		(pin "R7"
		)
		(pin "R8"
		)
		(pin "R9"
		)
		(pin "T10"
		)
		(pin "T2"
		)
		(pin "T3"
		)
		(pin "T4"
		)
		(pin "T5"
		)
		(pin "T6"
		)
		(pin "T7"
		)
		(pin "T8"
		)
		(pin "T9"
		)
		(pin "K7"
		)
		(pin "L6"
		)
		(pin "L7"
		)
		(pin "M4"
		)
		(pin "M7"
		)
		(pin "N3"
		)
		(pin "N4"
		)
		(pin "N5"
		)
		(pin "P1"
		)
		(pin "P2"
		)
		(pin "P3"
		)
		(pin "H1"
		)
		(pin "H2"
		)
		(pin "H3"
		)
		(pin "H4"
		)
		(pin "H5"
		)
		(pin "H6"
		)
		(pin "J1"
		)
		(pin "J2"
		)
		(pin "J4"
		)
		(pin "J5"
		)
		(pin "J6"
		)
		(pin "K1"
		)
		(pin "K2"
		)
		(pin "K3"
		)
		(pin "K4"
		)
		(pin "K5"
		)
		(pin "K6"
		)
		(pin "L1"
		)
		(pin "L2"
		)
		(pin "L3"
		)
		(pin "L4"
		)
		(pin "L5"
		)
		(pin "M1"
		)
		(pin "M2"
		)
		(pin "M3"
		)
		(pin "N1"
		)
		(pin "N2"
		)
		(pin "D4"
		)
		(pin "D5"
		)
		(pin "D6"
		)
		(pin "E4"
		)
		(pin "E5"
		)
		(pin "E6"
		)
		(pin "F4"
		)
		(pin "F5"
		)
		(pin "F6"
		)
		(pin "G3"
		)
		(pin "G4"
		)
		(pin "G6"
		)
		(pin "B1"
		)
		(pin "B2"
		)
		(pin "C1"
		)
		(pin "C2"
		)
		(pin "D1"
		)
		(pin "D2"
		)
		(pin "E1"
		)
		(pin "E2"
		)
		(pin "F1"
		)
		(pin "F2"
		)
		(pin "A3"
		)
		(pin "A4"
		)
		(pin "A5"
		)
		(pin "A6"
		)
		(pin "A7"
		)
		(pin "B3"
		)
		(pin "B4"
		)
		(pin "B5"
		)
		(pin "B6"
		)
		(pin "B7"
		)
		(pin "K13"
		)
		(pin "K14"
		)
		(pin "K15"
		)
		(pin "K16"
		)
		(pin "L13"
		)
		(pin "L14"
		)
		(pin "L15"
		)
		(pin "L16"
		)
		(pin "A11"
		)
		(pin "A12"
		)
		(pin "A14"
		)
		(pin "A15"
		)
		(pin "A9"
		)
		(pin "B12"
		)
		(pin "B9"
		)
		(pin "C11"
		)
		(pin "A1"
		)
		(pin "A10"
		)
		(pin "A13"
		)
		(pin "A16"
		)
		(pin "A2"
		)
		(pin "A8"
		)
		(pin "B10"
		)
		(pin "B11"
		)
		(pin "B13"
		)
		(pin "B14"
		)
		(pin "B15"
		)
		(pin "B8"
		)
		(pin "C10"
		)
		(pin "C3"
		)
		(pin "C4"
		)
		(pin "C5"
		)
		(pin "C6"
		)
		(pin "C7"
		)
		(pin "C8"
		)
		(pin "C9"
		)
		(pin "D14"
		)
		(pin "D3"
		)
		(pin "D7"
		)
		(pin "D8"
		)
		(pin "D9"
		)
		(pin "E3"
		)
		(pin "E7"
		)
		(pin "E8"
		)
		(pin "F12"
		)
		(pin "F3"
		)
		(pin "F7"
		)
		(pin "F8"
		)
		(pin "G1"
		)
		(pin "G2"
		)
		(pin "G5"
		)
		(pin "G7"
		)
		(pin "G8"
		)
		(pin "H7"
		)
		(pin "H8"
		)
		(pin "H9"
		)
		(pin "J10"
		)
		(pin "J14"
		)
		(pin "J3"
		)
		(pin "J7"
		)
		(pin "J8"
		)
		(pin "J9"
		)
		(pin "K10"
		)
		(pin "K8"
		)
		(pin "K9"
		)
		(pin "M5"
		)
		(pin "M6"
		)
		(pin "N7"
		)
		(pin "P13"
		)
		(pin "T1"
		)
		(pin "T16"
		)
		(instances
			(project "sdi-mipi-video-converter"
				(path ""
					(reference "U11")
					(unit 9)
				)
			)
		)
	)
	(symbol
		(lib_id "antmicroSlideSwitches:SW_CVS-02B")
		(at 382.27 143.51 180)
		(unit 1)
		(exclude_from_sim no)
		(in_bom yes)
		(on_board yes)
		(dnp no)
		(fields_autoplaced yes)
		(property "Reference" "SW1"
			(at 375.92 130.81 0)
			(effects
				(font
					(size 1.27 1.27)
					(thickness 0.15)
				)
			)
		)
		(property "Value" "SW_CVS-02B"
			(at 375.92 133.35 0)
			(effects
				(font
					(size 1.27 1.27)
					(thickness 0.15)
				)
			)
		)
		(property "Footprint" "antmicro-footprints:SW_DIP_SPSTx02_Slide_Copal_CVS-02xB_W5.9mm_P1mm"
			(at 355.6 135.89 0)
			(effects
				(font
					(size 1.27 1.27)
					(thickness 0.15)
				)
				(justify left bottom)
				(hide yes)
			)
		)
		(property "Datasheet" "https://www.mouser.com/datasheet/2/972/cvs-1827291.pdf"
			(at 355.6 133.35 0)
			(effects
				(font
					(size 1.27 1.27)
					(thickness 0.15)
				)
				(justify left bottom)
				(hide yes)
			)
		)
		(property "Description" "Slide switch, 2-position SMD Slide switch, 2-channel"
			(at 382.27 143.51 0)
			(effects
				(font
					(size 1.27 1.27)
				)
				(hide yes)
			)
		)
		(property "MPN" "CVS-02B"
			(at 355.6 130.81 0)
			(effects
				(font
					(size 1.27 1.27)
					(thickness 0.15)
				)
				(justify left bottom)
				(hide yes)
			)
		)
		(property "Manufacturer" "Nidec Components"
			(at 355.6 128.27 0)
			(effects
				(font
					(size 1.27 1.27)
					(thickness 0.15)
				)
				(justify left bottom)
				(hide yes)
			)
		)
		(property "Author" "Antmicro"
			(at 355.6 125.73 0)
			(effects
				(font
					(size 1.27 1.27)
					(thickness 0.15)
				)
				(justify left bottom)
				(hide yes)
			)
		)
		(property "License" "Apache-2.0"
			(at 355.6 123.19 0)
			(effects
				(font
					(size 1.27 1.27)
					(thickness 0.15)
				)
				(justify left bottom)
				(hide yes)
			)
		)
		(pin "1"
		)
		(pin "2"
		)
		(pin "3"
		)
		(pin "4"
		)
		(pin "SH"
		)
		(instances
			(project "sdi-mipi-video-converter"
				(path ""
					(reference "SW1")
					(unit 1)
				)
			)
		)
	)
	(symbol
		(lib_id "antmicroFPGAChips:CrossLink_LIFCL-40-9BG256C")
		(at 105.41 33.02 0)
		(mirror y)
		(unit 10)
		(exclude_from_sim no)
		(in_bom yes)
		(on_board yes)
		(dnp no)
		(fields_autoplaced yes)
		(property "Reference" "U11"
			(at 90.805 25.4 0)
			(effects
				(font
					(size 1.27 1.27)
					(thickness 0.15)
				)
			)
		)
		(property "Value" "LIFCL-40-9BG256C"
			(at 90.805 25.4 0)
			(effects
				(font
					(size 1.27 1.27)
					(thickness 0.15)
				)
				(hide yes)
			)
		)
		(property "Footprint" "antmicro-footprints:BGA-256_14x14mm_Layout16x16_P0.8mm"
			(at 52.07 40.64 0)
			(effects
				(font
					(size 1.27 1.27)
					(thickness 0.15)
				)
				(justify left bottom)
				(hide yes)
			)
		)
		(property "Datasheet" "https://www.latticesemi.com/-/media/LatticeSemi/Documents/DataSheets/CrossLink/FPGA-DS-02007-2-1-CrossLink-Family-Data-Sheet.ashx?document_id=51662"
			(at 52.07 43.18 0)
			(effects
				(font
					(size 1.27 1.27)
					(thickness 0.15)
				)
				(justify left bottom)
				(hide yes)
			)
		)
		(property "Description" "CrossLink-NX™ Field Programmable Gate Array 256-LFBGA"
			(at 105.41 33.02 0)
			(effects
				(font
					(size 1.27 1.27)
				)
				(hide yes)
			)
		)
		(property "MPN" "LIFCL-40-9BG256C"
			(at 90.805 27.94 0)
			(effects
				(font
					(size 1.27 1.27)
					(thickness 0.15)
				)
			)
		)
		(property "Manufacturer" "Lattice Semiconductor"
			(at 52.07 45.72 0)
			(effects
				(font
					(size 1.27 1.27)
					(thickness 0.15)
				)
				(justify left bottom)
				(hide yes)
			)
		)
		(property "Author" "Antmicro"
			(at 52.07 48.26 0)
			(effects
				(font
					(size 1.27 1.27)
					(thickness 0.15)
				)
				(justify left bottom)
				(hide yes)
			)
		)
		(property "License" "Apache-2.0"
			(at 52.07 50.8 0)
			(effects
				(font
					(size 1.27 1.27)
					(thickness 0.15)
				)
				(justify left bottom)
				(hide yes)
			)
		)
		(pin "B16"
		)
		(pin "C12"
		)
		(pin "C13"
		)
		(pin "C14"
		)
		(pin "C15"
		)
		(pin "C16"
		)
		(pin "D11"
		)
		(pin "D12"
		)
		(pin "D13"
		)
		(pin "D15"
		)
		(pin "D16"
		)
		(pin "E15"
		)
		(pin "E16"
		)
		(pin "D10"
		)
		(pin "E10"
		)
		(pin "E11"
		)
		(pin "E12"
		)
		(pin "E13"
		)
		(pin "E14"
		)
		(pin "E9"
		)
		(pin "F10"
		)
		(pin "F11"
		)
		(pin "F13"
		)
		(pin "F14"
		)
		(pin "F15"
		)
		(pin "F16"
		)
		(pin "F9"
		)
		(pin "G10"
		)
		(pin "G11"
		)
		(pin "G12"
		)
		(pin "G13"
		)
		(pin "G14"
		)
		(pin "G15"
		)
		(pin "G16"
		)
		(pin "G9"
		)
		(pin "H10"
		)
		(pin "H11"
		)
		(pin "H12"
		)
		(pin "H13"
		)
		(pin "H14"
		)
		(pin "H15"
		)
		(pin "H16"
		)
		(pin "J11"
		)
		(pin "J12"
		)
		(pin "J13"
		)
		(pin "J15"
		)
		(pin "J16"
		)
		(pin "K11"
		)
		(pin "K12"
		)
		(pin "L10"
		)
		(pin "L11"
		)
		(pin "L12"
		)
		(pin "M11"
		)
		(pin "M12"
		)
		(pin "M13"
		)
		(pin "M14"
		)
		(pin "M15"
		)
		(pin "M16"
		)
		(pin "N11"
		)
		(pin "N12"
		)
		(pin "N13"
		)
		(pin "N14"
		)
		(pin "N15"
		)
		(pin "N16"
		)
		(pin "P10"
		)
		(pin "P11"
		)
		(pin "P12"
		)
		(pin "P14"
		)
		(pin "P15"
		)
		(pin "P16"
		)
		(pin "R10"
		)
		(pin "R11"
		)
		(pin "R12"
		)
		(pin "R13"
		)
		(pin "R14"
		)
		(pin "R15"
		)
		(pin "R16"
		)
		(pin "T11"
		)
		(pin "T12"
		)
		(pin "T13"
		)
		(pin "T14"
		)
		(pin "T15"
		)
		(pin "L8"
		)
		(pin "L9"
		)
		(pin "M10"
		)
		(pin "M8"
		)
		(pin "M9"
		)
		(pin "N10"
		)
		(pin "N6"
		)
		(pin "N8"
		)
		(pin "N9"
		)
		(pin "P4"
		)
		(pin "P5"
		)
		(pin "P6"
		)
		(pin "P7"
		)
		(pin "P8"
		)
		(pin "P9"
		)
		(pin "R1"
		)
		(pin "R2"
		)
		(pin "R3"
		)
		(pin "R4"
		)
		(pin "R5"
		)
		(pin "R6"
		)
		(pin "R7"
		)
		(pin "R8"
		)
		(pin "R9"
		)
		(pin "T10"
		)
		(pin "T2"
		)
		(pin "T3"
		)
		(pin "T4"
		)
		(pin "T5"
		)
		(pin "T6"
		)
		(pin "T7"
		)
		(pin "T8"
		)
		(pin "T9"
		)
		(pin "K7"
		)
		(pin "L6"
		)
		(pin "L7"
		)
		(pin "M4"
		)
		(pin "M7"
		)
		(pin "N3"
		)
		(pin "N4"
		)
		(pin "N5"
		)
		(pin "P1"
		)
		(pin "P2"
		)
		(pin "P3"
		)
		(pin "H1"
		)
		(pin "H2"
		)
		(pin "H3"
		)
		(pin "H4"
		)
		(pin "H5"
		)
		(pin "H6"
		)
		(pin "J1"
		)
		(pin "J2"
		)
		(pin "J4"
		)
		(pin "J5"
		)
		(pin "J6"
		)
		(pin "K1"
		)
		(pin "K2"
		)
		(pin "K3"
		)
		(pin "K4"
		)
		(pin "K5"
		)
		(pin "K6"
		)
		(pin "L1"
		)
		(pin "L2"
		)
		(pin "L3"
		)
		(pin "L4"
		)
		(pin "L5"
		)
		(pin "M1"
		)
		(pin "M2"
		)
		(pin "M3"
		)
		(pin "N1"
		)
		(pin "N2"
		)
		(pin "D4"
		)
		(pin "D5"
		)
		(pin "D6"
		)
		(pin "E4"
		)
		(pin "E5"
		)
		(pin "E6"
		)
		(pin "F4"
		)
		(pin "F5"
		)
		(pin "F6"
		)
		(pin "G3"
		)
		(pin "G4"
		)
		(pin "G6"
		)
		(pin "B1"
		)
		(pin "B2"
		)
		(pin "C1"
		)
		(pin "C2"
		)
		(pin "D1"
		)
		(pin "D2"
		)
		(pin "E1"
		)
		(pin "E2"
		)
		(pin "F1"
		)
		(pin "F2"
		)
		(pin "A3"
		)
		(pin "A4"
		)
		(pin "A5"
		)
		(pin "A6"
		)
		(pin "A7"
		)
		(pin "B3"
		)
		(pin "B4"
		)
		(pin "B5"
		)
		(pin "B6"
		)
		(pin "B7"
		)
		(pin "K13"
		)
		(pin "K14"
		)
		(pin "K15"
		)
		(pin "K16"
		)
		(pin "L13"
		)
		(pin "L14"
		)
		(pin "L15"
		)
		(pin "L16"
		)
		(pin "A11"
		)
		(pin "A12"
		)
		(pin "A14"
		)
		(pin "A15"
		)
		(pin "A9"
		)
		(pin "B12"
		)
		(pin "B9"
		)
		(pin "C11"
		)
		(pin "A1"
		)
		(pin "A10"
		)
		(pin "A13"
		)
		(pin "A16"
		)
		(pin "A2"
		)
		(pin "A8"
		)
		(pin "B10"
		)
		(pin "B11"
		)
		(pin "B13"
		)
		(pin "B14"
		)
		(pin "B15"
		)
		(pin "B8"
		)
		(pin "C10"
		)
		(pin "C3"
		)
		(pin "C4"
		)
		(pin "C5"
		)
		(pin "C6"
		)
		(pin "C7"
		)
		(pin "C8"
		)
		(pin "C9"
		)
		(pin "D14"
		)
		(pin "D3"
		)
		(pin "D7"
		)
		(pin "D8"
		)
		(pin "D9"
		)
		(pin "E3"
		)
		(pin "E7"
		)
		(pin "E8"
		)
		(pin "F12"
		)
		(pin "F3"
		)
		(pin "F7"
		)
		(pin "F8"
		)
		(pin "G1"
		)
		(pin "G2"
		)
		(pin "G5"
		)
		(pin "G7"
		)
		(pin "G8"
		)
		(pin "H7"
		)
		(pin "H8"
		)
		(pin "H9"
		)
		(pin "J10"
		)
		(pin "J14"
		)
		(pin "J3"
		)
		(pin "J7"
		)
		(pin "J8"
		)
		(pin "J9"
		)
		(pin "K10"
		)
		(pin "K8"
		)
		(pin "K9"
		)
		(pin "M5"
		)
		(pin "M6"
		)
		(pin "N7"
		)
		(pin "P13"
		)
		(pin "T1"
		)
		(pin "T16"
		)
		(instances
			(project "sdi-mipi-video-converter"
				(path ""
					(reference "U11")
					(unit 10)
				)
			)
		)
	)
	(symbol
		(lib_id "antmicropower:GND")
		(at 318.77 157.48 0)
		(unit 1)
		(exclude_from_sim no)
		(in_bom yes)
		(on_board yes)
		(dnp no)
		(fields_autoplaced yes)
		(property "Reference" "#PWR0158"
			(at 327.66 160.02 0)
			(effects
				(font
					(size 1.27 1.27)
					(thickness 0.15)
				)
				(justify left bottom)
				(hide yes)
			)
		)
		(property "Value" "GND"
			(at 318.77 162.56 0)
			(effects
				(font
					(size 1.27 1.27)
					(thickness 0.15)
				)
			)
		)
		(property "Footprint" ""
			(at 327.66 165.1 0)
			(effects
				(font
					(size 1.27 1.27)
					(thickness 0.15)
				)
				(justify left bottom)
				(hide yes)
			)
		)
		(property "Datasheet" ""
			(at 327.66 170.18 0)
			(effects
				(font
					(size 1.27 1.27)
					(thickness 0.15)
				)
				(justify left bottom)
				(hide yes)
			)
		)
		(property "Description" ""
			(at 318.77 157.48 0)
			(effects
				(font
					(size 1.27 1.27)
				)
				(hide yes)
			)
		)
		(property "Author" "Antmicro"
			(at 327.66 165.1 0)
			(effects
				(font
					(size 1.27 1.27)
					(thickness 0.15)
				)
				(justify left bottom)
				(hide yes)
			)
		)
		(property "License" "Apache-2.0"
			(at 327.66 167.64 0)
			(effects
				(font
					(size 1.27 1.27)
					(thickness 0.15)
				)
				(justify left bottom)
				(hide yes)
			)
		)
		(pin "1"
		)
		(instances
			(project "sdi-mipi-video-converter"
				(path ""
					(reference "#PWR0158")
					(unit 1)
				)
			)
		)
	)
	(symbol
		(lib_id "antmicropower:GND")
		(at 179.07 176.53 0)
		(unit 1)
		(exclude_from_sim no)
		(in_bom yes)
		(on_board yes)
		(dnp no)
		(fields_autoplaced yes)
		(property "Reference" "#PWR0253"
			(at 187.96 179.07 0)
			(effects
				(font
					(size 1.27 1.27)
					(thickness 0.15)
				)
				(justify left bottom)
				(hide yes)
			)
		)
		(property "Value" "GND"
			(at 179.07 181.61 0)
			(effects
				(font
					(size 1.27 1.27)
					(thickness 0.15)
				)
			)
		)
		(property "Footprint" ""
			(at 187.96 184.15 0)
			(effects
				(font
					(size 1.27 1.27)
					(thickness 0.15)
				)
				(justify left bottom)
				(hide yes)
			)
		)
		(property "Datasheet" ""
			(at 187.96 189.23 0)
			(effects
				(font
					(size 1.27 1.27)
					(thickness 0.15)
				)
				(justify left bottom)
				(hide yes)
			)
		)
		(property "Description" ""
			(at 179.07 176.53 0)
			(effects
				(font
					(size 1.27 1.27)
				)
				(hide yes)
			)
		)
		(property "Author" "Antmicro"
			(at 187.96 184.15 0)
			(effects
				(font
					(size 1.27 1.27)
					(thickness 0.15)
				)
				(justify left bottom)
				(hide yes)
			)
		)
		(property "License" "Apache-2.0"
			(at 187.96 186.69 0)
			(effects
				(font
					(size 1.27 1.27)
					(thickness 0.15)
				)
				(justify left bottom)
				(hide yes)
			)
		)
		(pin "1"
		)
		(instances
			(project "sdi-mipi-video-converter"
				(path ""
					(reference "#PWR0253")
					(unit 1)
				)
			)
		)
	)
	(symbol
		(lib_id "antmicroInterfaceControllers:FT230X_QFN")
		(at 314.96 217.17 0)
		(unit 1)
		(exclude_from_sim no)
		(in_bom yes)
		(on_board yes)
		(dnp no)
		(fields_autoplaced yes)
		(property "Reference" "U20"
			(at 326.39 209.55 0)
			(effects
				(font
					(size 1.27 1.27)
					(thickness 0.15)
				)
			)
		)
		(property "Value" "FT230X_QFN"
			(at 326.39 212.09 0)
			(effects
				(font
					(size 1.27 1.27)
					(thickness 0.15)
				)
			)
		)
		(property "Footprint" "antmicro-footprints:QFN-16-1EP_4x4mm_P0.65mm"
			(at 354.33 229.87 0)
			(effects
				(font
					(size 1.27 1.27)
					(thickness 0.15)
				)
				(justify left bottom)
				(hide yes)
			)
		)
		(property "Datasheet" "https://ftdichip.com/wp-content/uploads/2021/10/DS_FT230X.pdf"
			(at 354.33 232.41 0)
			(effects
				(font
					(size 1.27 1.27)
					(thickness 0.15)
				)
				(justify left bottom)
				(hide yes)
			)
		)
		(property "Description" "USB Interface, USB-UART Converter, USB 2.0, 2.97 V, 5.5 V, QFN, 16 Pins"
			(at 314.96 217.17 0)
			(effects
				(font
					(size 1.27 1.27)
				)
				(hide yes)
			)
		)
		(property "Manufacturer" "FTDI Chip"
			(at 354.33 234.95 0)
			(effects
				(font
					(size 1.27 1.27)
					(thickness 0.15)
				)
				(justify left bottom)
				(hide yes)
			)
		)
		(property "MPN" "FT230XQ-R"
			(at 354.33 237.49 0)
			(effects
				(font
					(size 1.27 1.27)
					(thickness 0.15)
				)
				(justify left bottom)
				(hide yes)
			)
		)
		(property "Author" "Antmicro"
			(at 354.33 240.03 0)
			(effects
				(font
					(size 1.27 1.27)
					(thickness 0.15)
				)
				(justify left bottom)
				(hide yes)
			)
		)
		(property "License" "Apache-2.0"
			(at 354.33 242.57 0)
			(effects
				(font
					(size 1.27 1.27)
					(thickness 0.15)
				)
				(justify left bottom)
				(hide yes)
			)
		)
		(pin "1"
		)
		(pin "10"
		)
		(pin "11"
		)
		(pin "12"
		)
		(pin "13"
		)
		(pin "14"
		)
		(pin "15"
		)
		(pin "16"
		)
		(pin "17"
		)
		(pin "2"
		)
		(pin "3"
		)
		(pin "4"
		)
		(pin "5"
		)
		(pin "6"
		)
		(pin "7"
		)
		(pin "8"
		)
		(pin "9"
		)
		(instances
			(project "sdi-mipi-video-converter"
				(path ""
					(reference "U20")
					(unit 1)
				)
			)
		)
	)
	(symbol
		(lib_id "antmicropower:GND")
		(at 297.18 210.82 0)
		(unit 1)
		(exclude_from_sim no)
		(in_bom yes)
		(on_board yes)
		(dnp no)
		(fields_autoplaced yes)
		(property "Reference" "#PWR0267"
			(at 306.07 213.36 0)
			(effects
				(font
					(size 1.27 1.27)
					(thickness 0.15)
				)
				(justify left bottom)
				(hide yes)
			)
		)
		(property "Value" "GND"
			(at 297.18 215.9 0)
			(effects
				(font
					(size 1.27 1.27)
					(thickness 0.15)
				)
			)
		)
		(property "Footprint" ""
			(at 306.07 218.44 0)
			(effects
				(font
					(size 1.27 1.27)
					(thickness 0.15)
				)
				(justify left bottom)
				(hide yes)
			)
		)
		(property "Datasheet" ""
			(at 306.07 223.52 0)
			(effects
				(font
					(size 1.27 1.27)
					(thickness 0.15)
				)
				(justify left bottom)
				(hide yes)
			)
		)
		(property "Description" ""
			(at 297.18 210.82 0)
			(effects
				(font
					(size 1.27 1.27)
				)
				(hide yes)
			)
		)
		(property "Author" "Antmicro"
			(at 306.07 218.44 0)
			(effects
				(font
					(size 1.27 1.27)
					(thickness 0.15)
				)
				(justify left bottom)
				(hide yes)
			)
		)
		(property "License" "Apache-2.0"
			(at 306.07 220.98 0)
			(effects
				(font
					(size 1.27 1.27)
					(thickness 0.15)
				)
				(justify left bottom)
				(hide yes)
			)
		)
		(pin "1"
		)
		(instances
			(project "sdi-mipi-video-converter"
				(path ""
					(reference "#PWR0267")
					(unit 1)
				)
			)
		)
	)
	(symbol
		(lib_id "antmicroCapacitors0603:C_1u_0603")
		(at 285.75 209.55 90)
		(unit 1)
		(exclude_from_sim no)
		(in_bom yes)
		(on_board yes)
		(dnp no)
		(fields_autoplaced yes)
		(property "Reference" "C124"
			(at 288.29 205.7335 90)
			(effects
				(font
					(size 1.27 1.27)
					(thickness 0.15)
				)
				(justify right)
			)
		)
		(property "Value" "C_1u_0603"
			(at 295.91 189.23 0)
			(effects
				(font
					(size 1.27 1.27)
					(thickness 0.15)
				)
				(justify left bottom)
				(hide yes)
			)
		)
		(property "Footprint" "antmicro-footprints:C_0603_1608Metric"
			(at 298.45 189.23 0)
			(effects
				(font
					(size 1.27 1.27)
					(thickness 0.15)
				)
				(justify left bottom)
				(hide yes)
			)
		)
		(property "Datasheet" "https://spicat.kyocera-avx.com/product/mlcc/chartview/0603YD105KAT2A/"
			(at 300.99 189.23 0)
			(effects
				(font
					(size 1.27 1.27)
					(thickness 0.15)
				)
				(justify left bottom)
				(hide yes)
			)
		)
		(property "Description" "SMD Multilayer Ceramic Capacitor, 1 µF, 16 V, 0603 [1608 Metric], ± 10%, X5R, AVX 0603 MLCC"
			(at 285.75 209.55 0)
			(effects
				(font
					(size 1.27 1.27)
				)
				(hide yes)
			)
		)
		(property "Manufacturer" "KYOCERA AVX"
			(at 306.07 189.23 0)
			(effects
				(font
					(size 1.27 1.27)
					(thickness 0.15)
				)
				(justify left bottom)
				(hide yes)
			)
		)
		(property "MPN" "0603YD105KAT2A"
			(at 303.53 189.23 0)
			(effects
				(font
					(size 1.27 1.27)
					(thickness 0.15)
				)
				(justify left bottom)
				(hide yes)
			)
		)
		(property "Val" "1u"
			(at 288.29 208.2735 90)
			(effects
				(font
					(size 1.27 1.27)
					(thickness 0.15)
				)
				(justify right)
			)
		)
		(property "License" "Apache-2.0"
			(at 308.61 189.23 0)
			(effects
				(font
					(size 1.27 1.27)
					(thickness 0.15)
				)
				(justify left bottom)
				(hide yes)
			)
		)
		(property "Author" "Antmicro"
			(at 311.15 189.23 0)
			(effects
				(font
					(size 1.27 1.27)
					(thickness 0.15)
				)
				(justify left bottom)
				(hide yes)
			)
		)
		(property "Voltage" ""
			(at 313.69 189.23 0)
			(effects
				(font
					(size 1.27 1.27)
				)
				(justify left bottom)
				(hide yes)
			)
		)
		(property "Dielectric" ""
			(at 316.23 189.23 0)
			(effects
				(font
					(size 1.27 1.27)
				)
				(justify left bottom)
				(hide yes)
			)
		)
		(pin "1"
		)
		(pin "2"
		)
		(instances
			(project "sdi-mipi-video-converter"
				(path ""
					(reference "C124")
					(unit 1)
				)
			)
		)
	)
	(symbol
		(lib_id "antmicroResistors0402:R_0R_0402")
		(at 181.61 143.51 180)
		(unit 1)
		(exclude_from_sim no)
		(in_bom yes)
		(on_board yes)
		(dnp no)
		(property "Reference" "R125"
			(at 173.99 144.78 0)
			(effects
				(font
					(size 1.27 1.27)
					(thickness 0.15)
				)
			)
		)
		(property "Value" "R_0R_0402"
			(at 161.29 130.81 0)
			(effects
				(font
					(size 1.27 1.27)
					(thickness 0.15)
				)
				(justify left bottom)
				(hide yes)
			)
		)
		(property "Footprint" "antmicro-footprints:R_0402_1005Metric"
			(at 161.29 128.27 0)
			(effects
				(font
					(size 1.27 1.27)
					(thickness 0.15)
				)
				(justify left bottom)
				(hide yes)
			)
		)
		(property "Datasheet" "https://industrial.panasonic.com/cdbs/www-data/pdf/RDA0000/AOA0000C301.pdf"
			(at 161.29 125.73 0)
			(effects
				(font
					(size 1.27 1.27)
					(thickness 0.15)
				)
				(justify left bottom)
				(hide yes)
			)
		)
		(property "Description" "SMD Chip Resistor, Jumper, 0 ohm, 100 mW, 0402 [1005 Metric], Thick Film, General Purpose"
			(at 181.61 143.51 0)
			(effects
				(font
					(size 1.27 1.27)
				)
				(hide yes)
			)
		)
		(property "Manufacturer" "Panasonic"
			(at 161.29 120.65 0)
			(effects
				(font
					(size 1.27 1.27)
					(thickness 0.15)
				)
				(justify left bottom)
				(hide yes)
			)
		)
		(property "MPN" "ERJ2GE0R00X"
			(at 161.29 123.19 0)
			(effects
				(font
					(size 1.27 1.27)
					(thickness 0.15)
				)
				(justify left bottom)
				(hide yes)
			)
		)
		(property "Val" "0R"
			(at 182.88 144.78 0)
			(effects
				(font
					(size 1.27 1.27)
					(thickness 0.15)
				)
			)
		)
		(property "License" "Apache-2.0"
			(at 161.29 118.11 0)
			(effects
				(font
					(size 1.27 1.27)
					(thickness 0.15)
				)
				(justify left bottom)
				(hide yes)
			)
		)
		(property "Author" "Antmicro"
			(at 161.29 115.57 0)
			(effects
				(font
					(size 1.27 1.27)
					(thickness 0.15)
				)
				(justify left bottom)
				(hide yes)
			)
		)
		(property "Tolerance" "~"
			(at 161.29 133.35 0)
			(effects
				(font
					(size 1.27 1.27)
				)
				(justify left bottom)
				(hide yes)
			)
		)
		(property "Current" "1A"
			(at 161.29 113.03 0)
			(effects
				(font
					(size 1.27 1.27)
					(thickness 0.15)
				)
				(justify left bottom)
				(hide yes)
			)
		)
		(pin "1"
		)
		(pin "2"
		)
		(instances
			(project "sdi-mipi-video-converter"
				(path ""
					(reference "R125")
					(unit 1)
				)
			)
		)
	)
	(symbol
		(lib_id "antmicroResistors0402:R_5k1_0402")
		(at 271.78 220.98 180)
		(unit 1)
		(exclude_from_sim no)
		(in_bom yes)
		(on_board yes)
		(dnp no)
		(property "Reference" "R8"
			(at 265.43 219.71 0)
			(effects
				(font
					(size 1.27 1.27)
					(thickness 0.15)
				)
			)
		)
		(property "Value" "R_5k1_0402"
			(at 251.46 208.28 0)
			(effects
				(font
					(size 1.27 1.27)
					(thickness 0.15)
				)
				(justify left bottom)
				(hide yes)
			)
		)
		(property "Footprint" "antmicro-footprints:R_0402_1005Metric"
			(at 251.46 205.74 0)
			(effects
				(font
					(size 1.27 1.27)
					(thickness 0.15)
				)
				(justify left bottom)
				(hide yes)
			)
		)
		(property "Datasheet" "https://www.bourns.com/docs/product-datasheets/cr.pdf"
			(at 251.46 203.2 0)
			(effects
				(font
					(size 1.27 1.27)
					(thickness 0.15)
				)
				(justify left bottom)
				(hide yes)
			)
		)
		(property "Description" "SMD Chip Resistor, 5.1 kohm, ± 1%, 63 mW, 0402 [1005 Metric], Thick Film, General Purpose"
			(at 271.78 220.98 0)
			(effects
				(font
					(size 1.27 1.27)
				)
				(hide yes)
			)
		)
		(property "Manufacturer" "Bourns"
			(at 251.46 198.12 0)
			(effects
				(font
					(size 1.27 1.27)
					(thickness 0.15)
				)
				(justify left bottom)
				(hide yes)
			)
		)
		(property "MPN" "CR0402-FX-5101GLF"
			(at 251.46 200.66 0)
			(effects
				(font
					(size 1.27 1.27)
					(thickness 0.15)
				)
				(justify left bottom)
				(hide yes)
			)
		)
		(property "Val" "5k1"
			(at 273.685 219.71 0)
			(effects
				(font
					(size 1.27 1.27)
					(thickness 0.15)
				)
			)
		)
		(property "License" "Apache-2.0"
			(at 251.46 195.58 0)
			(effects
				(font
					(size 1.27 1.27)
					(thickness 0.15)
				)
				(justify left bottom)
				(hide yes)
			)
		)
		(property "Author" "Antmicro"
			(at 251.46 193.04 0)
			(effects
				(font
					(size 1.27 1.27)
					(thickness 0.15)
				)
				(justify left bottom)
				(hide yes)
			)
		)
		(property "Tolerance" "1%"
			(at 251.46 210.82 0)
			(effects
				(font
					(size 1.27 1.27)
				)
				(justify left bottom)
				(hide yes)
			)
		)
		(pin "1"
		)
		(pin "2"
		)
		(instances
			(project "sdi-mipi-video-converter"
				(path ""
					(reference "R8")
					(unit 1)
				)
			)
		)
	)
	(symbol
		(lib_id "antmicropower:GND")
		(at 148.59 271.78 0)
		(unit 1)
		(exclude_from_sim no)
		(in_bom yes)
		(on_board yes)
		(dnp no)
		(fields_autoplaced yes)
		(property "Reference" "#PWR0257"
			(at 157.48 274.32 0)
			(effects
				(font
					(size 1.27 1.27)
					(thickness 0.15)
				)
				(justify left bottom)
				(hide yes)
			)
		)
		(property "Value" "GND"
			(at 148.59 276.86 0)
			(effects
				(font
					(size 1.27 1.27)
					(thickness 0.15)
				)
			)
		)
		(property "Footprint" ""
			(at 157.48 279.4 0)
			(effects
				(font
					(size 1.27 1.27)
					(thickness 0.15)
				)
				(justify left bottom)
				(hide yes)
			)
		)
		(property "Datasheet" ""
			(at 157.48 284.48 0)
			(effects
				(font
					(size 1.27 1.27)
					(thickness 0.15)
				)
				(justify left bottom)
				(hide yes)
			)
		)
		(property "Description" ""
			(at 148.59 271.78 0)
			(effects
				(font
					(size 1.27 1.27)
				)
				(hide yes)
			)
		)
		(property "Author" "Antmicro"
			(at 157.48 279.4 0)
			(effects
				(font
					(size 1.27 1.27)
					(thickness 0.15)
				)
				(justify left bottom)
				(hide yes)
			)
		)
		(property "License" "Apache-2.0"
			(at 157.48 281.94 0)
			(effects
				(font
					(size 1.27 1.27)
					(thickness 0.15)
				)
				(justify left bottom)
				(hide yes)
			)
		)
		(pin "1"
		)
		(instances
			(project "sdi-mipi-video-converter"
				(path ""
					(reference "#PWR0257")
					(unit 1)
				)
			)
		)
	)
	(symbol
		(lib_id "antmicropower:GND")
		(at 53.34 240.03 0)
		(unit 1)
		(exclude_from_sim no)
		(in_bom yes)
		(on_board yes)
		(dnp no)
		(fields_autoplaced yes)
		(property "Reference" "#PWR06"
			(at 62.23 242.57 0)
			(effects
				(font
					(size 1.27 1.27)
					(thickness 0.15)
				)
				(justify left bottom)
				(hide yes)
			)
		)
		(property "Value" "GND"
			(at 53.34 245.11 0)
			(effects
				(font
					(size 1.27 1.27)
					(thickness 0.15)
				)
			)
		)
		(property "Footprint" ""
			(at 62.23 247.65 0)
			(effects
				(font
					(size 1.27 1.27)
					(thickness 0.15)
				)
				(justify left bottom)
				(hide yes)
			)
		)
		(property "Datasheet" ""
			(at 62.23 252.73 0)
			(effects
				(font
					(size 1.27 1.27)
					(thickness 0.15)
				)
				(justify left bottom)
				(hide yes)
			)
		)
		(property "Description" ""
			(at 53.34 240.03 0)
			(effects
				(font
					(size 1.27 1.27)
				)
				(hide yes)
			)
		)
		(property "Author" "Antmicro"
			(at 62.23 247.65 0)
			(effects
				(font
					(size 1.27 1.27)
					(thickness 0.15)
				)
				(justify left bottom)
				(hide yes)
			)
		)
		(property "License" "Apache-2.0"
			(at 62.23 250.19 0)
			(effects
				(font
					(size 1.27 1.27)
					(thickness 0.15)
				)
				(justify left bottom)
				(hide yes)
			)
		)
		(pin "1"
		)
		(instances
			(project "sdi-mipi-video-converter"
				(path ""
					(reference "#PWR06")
					(unit 1)
				)
			)
		)
	)
	(symbol
		(lib_id "antmicroResistors0402:R_27R_0402")
		(at 287.02 226.06 0)
		(mirror x)
		(unit 1)
		(exclude_from_sim no)
		(in_bom yes)
		(on_board yes)
		(dnp no)
		(property "Reference" "R134"
			(at 284.48 224.79 0)
			(effects
				(font
					(size 1.27 1.27)
					(thickness 0.15)
				)
			)
		)
		(property "Value" "R_27R_0402"
			(at 307.34 213.36 0)
			(effects
				(font
					(size 1.27 1.27)
					(thickness 0.15)
				)
				(justify left bottom)
				(hide yes)
			)
		)
		(property "Footprint" "antmicro-footprints:R_0402_1005Metric"
			(at 307.34 210.82 0)
			(effects
				(font
					(size 1.27 1.27)
					(thickness 0.15)
				)
				(justify left bottom)
				(hide yes)
			)
		)
		(property "Datasheet" "https://www.bourns.com/docs/product-datasheets/cr.pdf"
			(at 307.34 208.28 0)
			(effects
				(font
					(size 1.27 1.27)
					(thickness 0.15)
				)
				(justify left bottom)
				(hide yes)
			)
		)
		(property "Description" "SMD Chip Resistor, 27 ohm, ± 1%, 63 mW, 0402 [1005 Metric], Thick Film, General Purpose"
			(at 287.02 226.06 0)
			(effects
				(font
					(size 1.27 1.27)
				)
				(hide yes)
			)
		)
		(property "Manufacturer" "Bourns"
			(at 307.34 203.2 0)
			(effects
				(font
					(size 1.27 1.27)
					(thickness 0.15)
				)
				(justify left bottom)
				(hide yes)
			)
		)
		(property "MPN" "CR0402-FX-27R0GLF"
			(at 307.34 205.74 0)
			(effects
				(font
					(size 1.27 1.27)
					(thickness 0.15)
				)
				(justify left bottom)
				(hide yes)
			)
		)
		(property "Val" "27R"
			(at 294.005 224.79 0)
			(effects
				(font
					(size 1.27 1.27)
					(thickness 0.15)
				)
			)
		)
		(property "License" "Apache-2.0"
			(at 307.34 200.66 0)
			(effects
				(font
					(size 1.27 1.27)
					(thickness 0.15)
				)
				(justify left bottom)
				(hide yes)
			)
		)
		(property "Author" "Antmicro"
			(at 307.34 198.12 0)
			(effects
				(font
					(size 1.27 1.27)
					(thickness 0.15)
				)
				(justify left bottom)
				(hide yes)
			)
		)
		(property "Tolerance" "1%"
			(at 307.34 215.9 0)
			(effects
				(font
					(size 1.27 1.27)
				)
				(justify left bottom)
				(hide yes)
			)
		)
		(pin "1"
		)
		(pin "2"
		)
		(instances
			(project "sdi-mipi-video-converter"
				(path ""
					(reference "R134")
					(unit 1)
				)
			)
		)
	)
	(symbol
		(lib_id "antmicroResistors0402:R_0R_0402")
		(at 236.22 123.19 0)
		(unit 1)
		(exclude_from_sim no)
		(in_bom yes)
		(on_board yes)
		(dnp no)
		(property "Reference" "R130"
			(at 233.68 124.46 0)
			(effects
				(font
					(size 1.27 1.27)
					(thickness 0.15)
				)
			)
		)
		(property "Value" "R_0R_0402"
			(at 256.54 135.89 0)
			(effects
				(font
					(size 1.27 1.27)
					(thickness 0.15)
				)
				(justify left bottom)
				(hide yes)
			)
		)
		(property "Footprint" "antmicro-footprints:R_0402_1005Metric"
			(at 256.54 138.43 0)
			(effects
				(font
					(size 1.27 1.27)
					(thickness 0.15)
				)
				(justify left bottom)
				(hide yes)
			)
		)
		(property "Datasheet" "https://industrial.panasonic.com/cdbs/www-data/pdf/RDA0000/AOA0000C301.pdf"
			(at 256.54 140.97 0)
			(effects
				(font
					(size 1.27 1.27)
					(thickness 0.15)
				)
				(justify left bottom)
				(hide yes)
			)
		)
		(property "Description" "SMD Chip Resistor, Jumper, 0 ohm, 100 mW, 0402 [1005 Metric], Thick Film, General Purpose"
			(at 236.22 123.19 0)
			(effects
				(font
					(size 1.27 1.27)
				)
				(hide yes)
			)
		)
		(property "Manufacturer" "Panasonic"
			(at 256.54 146.05 0)
			(effects
				(font
					(size 1.27 1.27)
					(thickness 0.15)
				)
				(justify left bottom)
				(hide yes)
			)
		)
		(property "MPN" "ERJ2GE0R00X"
			(at 256.54 143.51 0)
			(effects
				(font
					(size 1.27 1.27)
					(thickness 0.15)
				)
				(justify left bottom)
				(hide yes)
			)
		)
		(property "Val" "0R"
			(at 242.57 124.46 0)
			(effects
				(font
					(size 1.27 1.27)
					(thickness 0.15)
				)
			)
		)
		(property "License" "Apache-2.0"
			(at 256.54 148.59 0)
			(effects
				(font
					(size 1.27 1.27)
					(thickness 0.15)
				)
				(justify left bottom)
				(hide yes)
			)
		)
		(property "Author" "Antmicro"
			(at 256.54 151.13 0)
			(effects
				(font
					(size 1.27 1.27)
					(thickness 0.15)
				)
				(justify left bottom)
				(hide yes)
			)
		)
		(property "Tolerance" "~"
			(at 256.54 133.35 0)
			(effects
				(font
					(size 1.27 1.27)
				)
				(justify left bottom)
				(hide yes)
			)
		)
		(property "Current" "1A"
			(at 256.54 153.67 0)
			(effects
				(font
					(size 1.27 1.27)
					(thickness 0.15)
				)
				(justify left bottom)
				(hide yes)
			)
		)
		(pin "1"
		)
		(pin "2"
		)
		(instances
			(project "sdi-mipi-video-converter"
				(path ""
					(reference "R130")
					(unit 1)
				)
			)
		)
	)
	(symbol
		(lib_id "antmicropower:GND")
		(at 87.63 213.36 0)
		(unit 1)
		(exclude_from_sim no)
		(in_bom yes)
		(on_board yes)
		(dnp no)
		(fields_autoplaced yes)
		(property "Reference" "#PWR015"
			(at 96.52 215.9 0)
			(effects
				(font
					(size 1.27 1.27)
					(thickness 0.15)
				)
				(justify left bottom)
				(hide yes)
			)
		)
		(property "Value" "GND"
			(at 87.63 218.44 0)
			(effects
				(font
					(size 1.27 1.27)
					(thickness 0.15)
				)
			)
		)
		(property "Footprint" ""
			(at 96.52 220.98 0)
			(effects
				(font
					(size 1.27 1.27)
					(thickness 0.15)
				)
				(justify left bottom)
				(hide yes)
			)
		)
		(property "Datasheet" ""
			(at 96.52 226.06 0)
			(effects
				(font
					(size 1.27 1.27)
					(thickness 0.15)
				)
				(justify left bottom)
				(hide yes)
			)
		)
		(property "Description" ""
			(at 87.63 213.36 0)
			(effects
				(font
					(size 1.27 1.27)
				)
				(hide yes)
			)
		)
		(property "Author" "Antmicro"
			(at 96.52 220.98 0)
			(effects
				(font
					(size 1.27 1.27)
					(thickness 0.15)
				)
				(justify left bottom)
				(hide yes)
			)
		)
		(property "License" "Apache-2.0"
			(at 96.52 223.52 0)
			(effects
				(font
					(size 1.27 1.27)
					(thickness 0.15)
				)
				(justify left bottom)
				(hide yes)
			)
		)
		(pin "1"
		)
		(instances
			(project "sdi-mipi-video-converter"
				(path ""
					(reference "#PWR015")
					(unit 1)
				)
			)
		)
	)
	(symbol
		(lib_id "antmicroResistors0603:R_0R_0603")
		(at 25.4 205.74 0)
		(unit 1)
		(exclude_from_sim no)
		(in_bom yes)
		(on_board yes)
		(dnp no)
		(property "Reference" "R116"
			(at 27.94 201.93 0)
			(effects
				(font
					(size 1.27 1.27)
					(thickness 0.15)
				)
			)
		)
		(property "Value" "R_0R_0603"
			(at 45.72 218.44 0)
			(effects
				(font
					(size 1.27 1.27)
					(thickness 0.15)
				)
				(justify left bottom)
				(hide yes)
			)
		)
		(property "Footprint" "antmicro-footprints:R_0603_1608Metric"
			(at 45.72 220.98 0)
			(effects
				(font
					(size 1.27 1.27)
					(thickness 0.15)
				)
				(justify left bottom)
				(hide yes)
			)
		)
		(property "Datasheet" "https://www.bourns.com/docs/product-datasheets/cr.pdf?sfvrsn=574d41f6_14"
			(at 45.72 223.52 0)
			(effects
				(font
					(size 1.27 1.27)
					(thickness 0.15)
				)
				(justify left bottom)
				(hide yes)
			)
		)
		(property "Description" "Zero Ohm Resistor, Jumper, 0603 [1608 Metric], Thick Film, 100 mW, 1 A, Surface Mount Device, CR"
			(at 25.4 205.74 0)
			(effects
				(font
					(size 1.27 1.27)
				)
				(hide yes)
			)
		)
		(property "Manufacturer" "Bourns"
			(at 45.72 228.6 0)
			(effects
				(font
					(size 1.27 1.27)
					(thickness 0.15)
				)
				(justify left bottom)
				(hide yes)
			)
		)
		(property "MPN" "CR0603-J/-000ELF"
			(at 45.72 226.06 0)
			(effects
				(font
					(size 1.27 1.27)
					(thickness 0.15)
				)
				(justify left bottom)
				(hide yes)
			)
		)
		(property "Val" "0R"
			(at 27.94 203.835 0)
			(effects
				(font
					(size 1.27 1.27)
					(thickness 0.15)
				)
			)
		)
		(property "License" "Apache-2.0"
			(at 45.72 231.14 0)
			(effects
				(font
					(size 1.27 1.27)
					(thickness 0.15)
				)
				(justify left bottom)
				(hide yes)
			)
		)
		(property "Author" "Antmicro"
			(at 45.72 233.68 0)
			(effects
				(font
					(size 1.27 1.27)
					(thickness 0.15)
				)
				(justify left bottom)
				(hide yes)
			)
		)
		(property "Tolerance" "~"
			(at 45.72 215.9 0)
			(effects
				(font
					(size 1.27 1.27)
				)
				(justify left bottom)
				(hide yes)
			)
		)
		(property "Current" "1A"
			(at 45.72 236.22 0)
			(effects
				(font
					(size 1.27 1.27)
					(thickness 0.15)
				)
				(justify left bottom)
				(hide yes)
			)
		)
		(pin "1"
		)
		(pin "2"
		)
		(instances
			(project "sdi-mipi-video-converter"
				(path ""
					(reference "R116")
					(unit 1)
				)
			)
		)
	)
	(symbol
		(lib_id "antmicroResistors0603:R_470R_0603")
		(at 158.75 166.37 90)
		(unit 1)
		(exclude_from_sim no)
		(in_bom yes)
		(on_board yes)
		(dnp no)
		(property "Reference" "R103"
			(at 160.02 162.56 90)
			(effects
				(font
					(size 1.27 1.27)
					(thickness 0.15)
				)
				(justify right)
			)
		)
		(property "Value" "R_470R_0603"
			(at 171.45 146.05 0)
			(effects
				(font
					(size 1.27 1.27)
					(thickness 0.15)
				)
				(justify left bottom)
				(hide yes)
			)
		)
		(property "Footprint" "antmicro-footprints:R_0603_1608Metric"
			(at 173.99 146.05 0)
			(effects
				(font
					(size 1.27 1.27)
					(thickness 0.15)
				)
				(justify left bottom)
				(hide yes)
			)
		)
		(property "Datasheet" "https://www.bourns.com/docs/product-datasheets/cr.pdf"
			(at 176.53 146.05 0)
			(effects
				(font
					(size 1.27 1.27)
					(thickness 0.15)
				)
				(justify left bottom)
				(hide yes)
			)
		)
		(property "Description" "SMD Chip Resistor, 470 ohm, ± 1%, 100 mW, 0603 [1608 Metric], Thick Film, General Purpose"
			(at 158.75 166.37 0)
			(effects
				(font
					(size 1.27 1.27)
				)
				(hide yes)
			)
		)
		(property "Manufacturer" "Bourns"
			(at 181.61 146.05 0)
			(effects
				(font
					(size 1.27 1.27)
					(thickness 0.15)
				)
				(justify left bottom)
				(hide yes)
			)
		)
		(property "MPN" "CR0603-FX-4700ELF"
			(at 179.07 146.05 0)
			(effects
				(font
					(size 1.27 1.27)
					(thickness 0.15)
				)
				(justify left bottom)
				(hide yes)
			)
		)
		(property "Val" "470R"
			(at 160.02 165.1 90)
			(effects
				(font
					(size 1.27 1.27)
					(thickness 0.15)
				)
				(justify right)
			)
		)
		(property "License" "Apache-2.0"
			(at 184.15 146.05 0)
			(effects
				(font
					(size 1.27 1.27)
					(thickness 0.15)
				)
				(justify left bottom)
				(hide yes)
			)
		)
		(property "Author" "Antmicro"
			(at 186.69 146.05 0)
			(effects
				(font
					(size 1.27 1.27)
					(thickness 0.15)
				)
				(justify left bottom)
				(hide yes)
			)
		)
		(property "Tolerance" "1%"
			(at 168.91 146.05 0)
			(effects
				(font
					(size 1.27 1.27)
				)
				(justify left bottom)
				(hide yes)
			)
		)
		(pin "1"
		)
		(pin "2"
		)
		(instances
			(project "sdi-mipi-video-converter"
				(path ""
					(reference "R103")
					(unit 1)
				)
			)
		)
	)
	(symbol
		(lib_id "antmicroTestPoints:TP_0.75mm_SMD")
		(at 157.48 265.43 270)
		(unit 1)
		(exclude_from_sim no)
		(in_bom yes)
		(on_board yes)
		(dnp no)
		(fields_autoplaced yes)
		(property "Reference" "TP44"
			(at 154.94 268.6049 90)
			(effects
				(font
					(size 1.27 1.27)
					(thickness 0.15)
				)
				(justify right)
			)
		)
		(property "Value" "TP_0.75mm_SMD"
			(at 149.86 283.21 0)
			(effects
				(font
					(size 1.27 1.27)
					(thickness 0.15)
				)
				(justify left bottom)
				(hide yes)
			)
		)
		(property "Footprint" "antmicro-footprints:TP_SMD_0.75mm"
			(at 147.32 283.21 0)
			(effects
				(font
					(size 1.27 1.27)
					(thickness 0.15)
				)
				(justify left bottom)
				(hide yes)
			)
		)
		(property "Datasheet" ""
			(at 144.78 283.21 0)
			(effects
				(font
					(size 1.27 1.27)
					(thickness 0.15)
				)
				(justify left bottom)
				(hide yes)
			)
		)
		(property "Description" "SMT test point"
			(at 157.48 265.43 0)
			(effects
				(font
					(size 1.27 1.27)
				)
				(hide yes)
			)
		)
		(property "MPN" ""
			(at 142.24 283.21 0)
			(effects
				(font
					(size 1.27 1.27)
					(thickness 0.15)
				)
				(justify left bottom)
				(hide yes)
			)
		)
		(property "Manufacturer" ""
			(at 139.7 283.21 0)
			(effects
				(font
					(size 1.27 1.27)
					(thickness 0.15)
				)
				(justify left bottom)
				(hide yes)
			)
		)
		(property "Author" "Antmicro"
			(at 137.16 283.21 0)
			(effects
				(font
					(size 1.27 1.27)
					(thickness 0.15)
				)
				(justify left bottom)
				(hide yes)
			)
		)
		(property "License" "Apache-2.0"
			(at 134.62 283.21 0)
			(effects
				(font
					(size 1.27 1.27)
					(thickness 0.15)
				)
				(justify left bottom)
				(hide yes)
			)
		)
		(pin "1"
		)
		(instances
			(project "sdi-mipi-video-converter"
				(path ""
					(reference "TP44")
					(unit 1)
				)
			)
		)
	)
	(symbol
		(lib_id "antmicropower:GND")
		(at 114.3 137.16 0)
		(unit 1)
		(exclude_from_sim no)
		(in_bom yes)
		(on_board yes)
		(dnp no)
		(fields_autoplaced yes)
		(property "Reference" "#PWR0151"
			(at 123.19 139.7 0)
			(effects
				(font
					(size 1.27 1.27)
					(thickness 0.15)
				)
				(justify left bottom)
				(hide yes)
			)
		)
		(property "Value" "GND"
			(at 114.3 142.24 0)
			(effects
				(font
					(size 1.27 1.27)
					(thickness 0.15)
				)
			)
		)
		(property "Footprint" ""
			(at 123.19 144.78 0)
			(effects
				(font
					(size 1.27 1.27)
					(thickness 0.15)
				)
				(justify left bottom)
				(hide yes)
			)
		)
		(property "Datasheet" ""
			(at 123.19 149.86 0)
			(effects
				(font
					(size 1.27 1.27)
					(thickness 0.15)
				)
				(justify left bottom)
				(hide yes)
			)
		)
		(property "Description" ""
			(at 114.3 137.16 0)
			(effects
				(font
					(size 1.27 1.27)
				)
				(hide yes)
			)
		)
		(property "Author" "Antmicro"
			(at 123.19 144.78 0)
			(effects
				(font
					(size 1.27 1.27)
					(thickness 0.15)
				)
				(justify left bottom)
				(hide yes)
			)
		)
		(property "License" "Apache-2.0"
			(at 123.19 147.32 0)
			(effects
				(font
					(size 1.27 1.27)
					(thickness 0.15)
				)
				(justify left bottom)
				(hide yes)
			)
		)
		(pin "1"
		)
		(instances
			(project "sdi-mipi-video-converter"
				(path ""
					(reference "#PWR0151")
					(unit 1)
				)
			)
		)
	)
	(symbol
		(lib_id "antmicroLEDIndicationDiscrete:LED_G_0603_LTST-C190GKT")
		(at 318.77 154.94 270)
		(mirror x)
		(unit 1)
		(exclude_from_sim no)
		(in_bom yes)
		(on_board yes)
		(dnp no)
		(fields_autoplaced yes)
		(property "Reference" "D4"
			(at 322.58 151.13 90)
			(effects
				(font
					(size 1.27 1.27)
					(thickness 0.15)
				)
				(justify left)
			)
		)
		(property "Value" "LED_G_0603_LTST-C190GKT"
			(at 322.58 153.67 90)
			(effects
				(font
					(size 1.27 1.27)
					(thickness 0.15)
				)
				(justify left)
			)
		)
		(property "Footprint" "antmicro-footprints:LED_0603_1608Metric_G"
			(at 308.61 132.08 0)
			(effects
				(font
					(size 1.27 1.27)
					(thickness 0.15)
				)
				(justify left bottom)
				(hide yes)
			)
		)
		(property "Datasheet" "https://media.digikey.com/pdf/Data%20Sheets/Lite-On%20PDFs/LTST-C190GKT.pdf"
			(at 306.07 132.08 0)
			(effects
				(font
					(size 1.27 1.27)
					(thickness 0.15)
				)
				(justify left bottom)
				(hide yes)
			)
		)
		(property "Description" "LED, Green, SMD, 0603, 20 mA, 2.1 V, 569 nm"
			(at 318.77 154.94 0)
			(effects
				(font
					(size 1.27 1.27)
				)
				(hide yes)
			)
		)
		(property "MPN" "LTST-C190GKT"
			(at 303.53 132.08 0)
			(effects
				(font
					(size 1.27 1.27)
					(thickness 0.15)
				)
				(justify left bottom)
				(hide yes)
			)
		)
		(property "Manufacturer" "Lite-On"
			(at 300.99 132.08 0)
			(effects
				(font
					(size 1.27 1.27)
					(thickness 0.15)
				)
				(justify left bottom)
				(hide yes)
			)
		)
		(property "Author" "Antmicro"
			(at 298.45 132.08 0)
			(effects
				(font
					(size 1.27 1.27)
					(thickness 0.15)
				)
				(justify left bottom)
				(hide yes)
			)
		)
		(property "License" "Apache-2.0"
			(at 295.91 132.08 0)
			(effects
				(font
					(size 1.27 1.27)
					(thickness 0.15)
				)
				(justify left bottom)
				(hide yes)
			)
		)
		(property "Color" "Green"
			(at 313.69 132.08 0)
			(effects
				(font
					(size 1.27 1.27)
				)
				(justify left bottom)
				(hide yes)
			)
		)
		(pin "1"
		)
		(pin "2"
		)
		(instances
			(project "sdi-mipi-video-converter"
				(path ""
					(reference "D4")
					(unit 1)
				)
			)
		)
	)
	(symbol
		(lib_id "antmicropower:GND")
		(at 193.04 234.95 0)
		(unit 1)
		(exclude_from_sim no)
		(in_bom yes)
		(on_board yes)
		(dnp no)
		(fields_autoplaced yes)
		(property "Reference" "#PWR0255"
			(at 201.93 237.49 0)
			(effects
				(font
					(size 1.27 1.27)
					(thickness 0.15)
				)
				(justify left bottom)
				(hide yes)
			)
		)
		(property "Value" "GND"
			(at 193.04 240.03 0)
			(effects
				(font
					(size 1.27 1.27)
					(thickness 0.15)
				)
			)
		)
		(property "Footprint" ""
			(at 201.93 242.57 0)
			(effects
				(font
					(size 1.27 1.27)
					(thickness 0.15)
				)
				(justify left bottom)
				(hide yes)
			)
		)
		(property "Datasheet" ""
			(at 201.93 247.65 0)
			(effects
				(font
					(size 1.27 1.27)
					(thickness 0.15)
				)
				(justify left bottom)
				(hide yes)
			)
		)
		(property "Description" ""
			(at 193.04 234.95 0)
			(effects
				(font
					(size 1.27 1.27)
				)
				(hide yes)
			)
		)
		(property "Author" "Antmicro"
			(at 201.93 242.57 0)
			(effects
				(font
					(size 1.27 1.27)
					(thickness 0.15)
				)
				(justify left bottom)
				(hide yes)
			)
		)
		(property "License" "Apache-2.0"
			(at 201.93 245.11 0)
			(effects
				(font
					(size 1.27 1.27)
					(thickness 0.15)
				)
				(justify left bottom)
				(hide yes)
			)
		)
		(pin "1"
		)
		(instances
			(project "sdi-mipi-video-converter"
				(path ""
					(reference "#PWR0255")
					(unit 1)
				)
			)
		)
	)
	(symbol
		(lib_id "antmicroCapacitors0603:C_1u_0603")
		(at 179.07 171.45 90)
		(unit 1)
		(exclude_from_sim no)
		(in_bom yes)
		(on_board yes)
		(dnp no)
		(fields_autoplaced yes)
		(property "Reference" "C112"
			(at 181.61 167.6335 90)
			(effects
				(font
					(size 1.27 1.27)
					(thickness 0.15)
				)
				(justify right)
			)
		)
		(property "Value" "C_1u_0603"
			(at 189.23 151.13 0)
			(effects
				(font
					(size 1.27 1.27)
					(thickness 0.15)
				)
				(justify left bottom)
				(hide yes)
			)
		)
		(property "Footprint" "antmicro-footprints:C_0603_1608Metric"
			(at 191.77 151.13 0)
			(effects
				(font
					(size 1.27 1.27)
					(thickness 0.15)
				)
				(justify left bottom)
				(hide yes)
			)
		)
		(property "Datasheet" "https://spicat.kyocera-avx.com/product/mlcc/chartview/0603YD105KAT2A/"
			(at 194.31 151.13 0)
			(effects
				(font
					(size 1.27 1.27)
					(thickness 0.15)
				)
				(justify left bottom)
				(hide yes)
			)
		)
		(property "Description" "SMD Multilayer Ceramic Capacitor, 1 µF, 16 V, 0603 [1608 Metric], ± 10%, X5R, AVX 0603 MLCC"
			(at 179.07 171.45 0)
			(effects
				(font
					(size 1.27 1.27)
				)
				(hide yes)
			)
		)
		(property "Manufacturer" "KYOCERA AVX"
			(at 199.39 151.13 0)
			(effects
				(font
					(size 1.27 1.27)
					(thickness 0.15)
				)
				(justify left bottom)
				(hide yes)
			)
		)
		(property "MPN" "0603YD105KAT2A"
			(at 196.85 151.13 0)
			(effects
				(font
					(size 1.27 1.27)
					(thickness 0.15)
				)
				(justify left bottom)
				(hide yes)
			)
		)
		(property "Val" "1u"
			(at 181.61 170.1735 90)
			(effects
				(font
					(size 1.27 1.27)
					(thickness 0.15)
				)
				(justify right)
			)
		)
		(property "License" "Apache-2.0"
			(at 201.93 151.13 0)
			(effects
				(font
					(size 1.27 1.27)
					(thickness 0.15)
				)
				(justify left bottom)
				(hide yes)
			)
		)
		(property "Author" "Antmicro"
			(at 204.47 151.13 0)
			(effects
				(font
					(size 1.27 1.27)
					(thickness 0.15)
				)
				(justify left bottom)
				(hide yes)
			)
		)
		(property "Voltage" ""
			(at 207.01 151.13 0)
			(effects
				(font
					(size 1.27 1.27)
				)
				(justify left bottom)
				(hide yes)
			)
		)
		(property "Dielectric" ""
			(at 209.55 151.13 0)
			(effects
				(font
					(size 1.27 1.27)
				)
				(justify left bottom)
				(hide yes)
			)
		)
		(pin "1"
		)
		(pin "2"
		)
		(instances
			(project "sdi-mipi-video-converter"
				(path ""
					(reference "C112")
					(unit 1)
				)
			)
		)
	)
	(symbol
		(lib_id "antmicroFPGAChips:CrossLink_LIFCL-40-9BG256C")
		(at 78.74 125.73 0)
		(mirror y)
		(unit 2)
		(exclude_from_sim no)
		(in_bom yes)
		(on_board yes)
		(dnp no)
		(fields_autoplaced yes)
		(property "Reference" "U11"
			(at 55.88 118.11 0)
			(effects
				(font
					(size 1.27 1.27)
					(thickness 0.15)
				)
			)
		)
		(property "Value" "LIFCL-40-9BG256C"
			(at 55.88 118.11 0)
			(effects
				(font
					(size 1.27 1.27)
					(thickness 0.15)
				)
				(hide yes)
			)
		)
		(property "Footprint" "antmicro-footprints:BGA-256_14x14mm_Layout16x16_P0.8mm"
			(at 25.4 133.35 0)
			(effects
				(font
					(size 1.27 1.27)
					(thickness 0.15)
				)
				(justify left bottom)
				(hide yes)
			)
		)
		(property "Datasheet" "https://www.latticesemi.com/-/media/LatticeSemi/Documents/DataSheets/CrossLink/FPGA-DS-02007-2-1-CrossLink-Family-Data-Sheet.ashx?document_id=51662"
			(at 25.4 135.89 0)
			(effects
				(font
					(size 1.27 1.27)
					(thickness 0.15)
				)
				(justify left bottom)
				(hide yes)
			)
		)
		(property "Description" "CrossLink-NX™ Field Programmable Gate Array 256-LFBGA"
			(at 78.74 125.73 0)
			(effects
				(font
					(size 1.27 1.27)
				)
				(hide yes)
			)
		)
		(property "MPN" "LIFCL-40-9BG256C"
			(at 55.88 120.65 0)
			(effects
				(font
					(size 1.27 1.27)
					(thickness 0.15)
				)
			)
		)
		(property "Manufacturer" "Lattice Semiconductor"
			(at 25.4 138.43 0)
			(effects
				(font
					(size 1.27 1.27)
					(thickness 0.15)
				)
				(justify left bottom)
				(hide yes)
			)
		)
		(property "Author" "Antmicro"
			(at 25.4 140.97 0)
			(effects
				(font
					(size 1.27 1.27)
					(thickness 0.15)
				)
				(justify left bottom)
				(hide yes)
			)
		)
		(property "License" "Apache-2.0"
			(at 25.4 143.51 0)
			(effects
				(font
					(size 1.27 1.27)
					(thickness 0.15)
				)
				(justify left bottom)
				(hide yes)
			)
		)
		(pin "B16"
		)
		(pin "C12"
		)
		(pin "C13"
		)
		(pin "C14"
		)
		(pin "C15"
		)
		(pin "C16"
		)
		(pin "D11"
		)
		(pin "D12"
		)
		(pin "D13"
		)
		(pin "D15"
		)
		(pin "D16"
		)
		(pin "E15"
		)
		(pin "E16"
		)
		(pin "D10"
		)
		(pin "E10"
		)
		(pin "E11"
		)
		(pin "E12"
		)
		(pin "E13"
		)
		(pin "E14"
		)
		(pin "E9"
		)
		(pin "F10"
		)
		(pin "F11"
		)
		(pin "F13"
		)
		(pin "F14"
		)
		(pin "F15"
		)
		(pin "F16"
		)
		(pin "F9"
		)
		(pin "G10"
		)
		(pin "G11"
		)
		(pin "G12"
		)
		(pin "G13"
		)
		(pin "G14"
		)
		(pin "G15"
		)
		(pin "G16"
		)
		(pin "G9"
		)
		(pin "H10"
		)
		(pin "H11"
		)
		(pin "H12"
		)
		(pin "H13"
		)
		(pin "H14"
		)
		(pin "H15"
		)
		(pin "H16"
		)
		(pin "J11"
		)
		(pin "J12"
		)
		(pin "J13"
		)
		(pin "J15"
		)
		(pin "J16"
		)
		(pin "K11"
		)
		(pin "K12"
		)
		(pin "L10"
		)
		(pin "L11"
		)
		(pin "L12"
		)
		(pin "M11"
		)
		(pin "M12"
		)
		(pin "M13"
		)
		(pin "M14"
		)
		(pin "M15"
		)
		(pin "M16"
		)
		(pin "N11"
		)
		(pin "N12"
		)
		(pin "N13"
		)
		(pin "N14"
		)
		(pin "N15"
		)
		(pin "N16"
		)
		(pin "P10"
		)
		(pin "P11"
		)
		(pin "P12"
		)
		(pin "P14"
		)
		(pin "P15"
		)
		(pin "P16"
		)
		(pin "R10"
		)
		(pin "R11"
		)
		(pin "R12"
		)
		(pin "R13"
		)
		(pin "R14"
		)
		(pin "R15"
		)
		(pin "R16"
		)
		(pin "T11"
		)
		(pin "T12"
		)
		(pin "T13"
		)
		(pin "T14"
		)
		(pin "T15"
		)
		(pin "L8"
		)
		(pin "L9"
		)
		(pin "M10"
		)
		(pin "M8"
		)
		(pin "M9"
		)
		(pin "N10"
		)
		(pin "N6"
		)
		(pin "N8"
		)
		(pin "N9"
		)
		(pin "P4"
		)
		(pin "P5"
		)
		(pin "P6"
		)
		(pin "P7"
		)
		(pin "P8"
		)
		(pin "P9"
		)
		(pin "R1"
		)
		(pin "R2"
		)
		(pin "R3"
		)
		(pin "R4"
		)
		(pin "R5"
		)
		(pin "R6"
		)
		(pin "R7"
		)
		(pin "R8"
		)
		(pin "R9"
		)
		(pin "T10"
		)
		(pin "T2"
		)
		(pin "T3"
		)
		(pin "T4"
		)
		(pin "T5"
		)
		(pin "T6"
		)
		(pin "T7"
		)
		(pin "T8"
		)
		(pin "T9"
		)
		(pin "K7"
		)
		(pin "L6"
		)
		(pin "L7"
		)
		(pin "M4"
		)
		(pin "M7"
		)
		(pin "N3"
		)
		(pin "N4"
		)
		(pin "N5"
		)
		(pin "P1"
		)
		(pin "P2"
		)
		(pin "P3"
		)
		(pin "H1"
		)
		(pin "H2"
		)
		(pin "H3"
		)
		(pin "H4"
		)
		(pin "H5"
		)
		(pin "H6"
		)
		(pin "J1"
		)
		(pin "J2"
		)
		(pin "J4"
		)
		(pin "J5"
		)
		(pin "J6"
		)
		(pin "K1"
		)
		(pin "K2"
		)
		(pin "K3"
		)
		(pin "K4"
		)
		(pin "K5"
		)
		(pin "K6"
		)
		(pin "L1"
		)
		(pin "L2"
		)
		(pin "L3"
		)
		(pin "L4"
		)
		(pin "L5"
		)
		(pin "M1"
		)
		(pin "M2"
		)
		(pin "M3"
		)
		(pin "N1"
		)
		(pin "N2"
		)
		(pin "D4"
		)
		(pin "D5"
		)
		(pin "D6"
		)
		(pin "E4"
		)
		(pin "E5"
		)
		(pin "E6"
		)
		(pin "F4"
		)
		(pin "F5"
		)
		(pin "F6"
		)
		(pin "G3"
		)
		(pin "G4"
		)
		(pin "G6"
		)
		(pin "B1"
		)
		(pin "B2"
		)
		(pin "C1"
		)
		(pin "C2"
		)
		(pin "D1"
		)
		(pin "D2"
		)
		(pin "E1"
		)
		(pin "E2"
		)
		(pin "F1"
		)
		(pin "F2"
		)
		(pin "A3"
		)
		(pin "A4"
		)
		(pin "A5"
		)
		(pin "A6"
		)
		(pin "A7"
		)
		(pin "B3"
		)
		(pin "B4"
		)
		(pin "B5"
		)
		(pin "B6"
		)
		(pin "B7"
		)
		(pin "K13"
		)
		(pin "K14"
		)
		(pin "K15"
		)
		(pin "K16"
		)
		(pin "L13"
		)
		(pin "L14"
		)
		(pin "L15"
		)
		(pin "L16"
		)
		(pin "A11"
		)
		(pin "A12"
		)
		(pin "A14"
		)
		(pin "A15"
		)
		(pin "A9"
		)
		(pin "B12"
		)
		(pin "B9"
		)
		(pin "C11"
		)
		(pin "A1"
		)
		(pin "A10"
		)
		(pin "A13"
		)
		(pin "A16"
		)
		(pin "A2"
		)
		(pin "A8"
		)
		(pin "B10"
		)
		(pin "B11"
		)
		(pin "B13"
		)
		(pin "B14"
		)
		(pin "B15"
		)
		(pin "B8"
		)
		(pin "C10"
		)
		(pin "C3"
		)
		(pin "C4"
		)
		(pin "C5"
		)
		(pin "C6"
		)
		(pin "C7"
		)
		(pin "C8"
		)
		(pin "C9"
		)
		(pin "D14"
		)
		(pin "D3"
		)
		(pin "D7"
		)
		(pin "D8"
		)
		(pin "D9"
		)
		(pin "E3"
		)
		(pin "E7"
		)
		(pin "E8"
		)
		(pin "F12"
		)
		(pin "F3"
		)
		(pin "F7"
		)
		(pin "F8"
		)
		(pin "G1"
		)
		(pin "G2"
		)
		(pin "G5"
		)
		(pin "G7"
		)
		(pin "G8"
		)
		(pin "H7"
		)
		(pin "H8"
		)
		(pin "H9"
		)
		(pin "J10"
		)
		(pin "J14"
		)
		(pin "J3"
		)
		(pin "J7"
		)
		(pin "J8"
		)
		(pin "J9"
		)
		(pin "K10"
		)
		(pin "K8"
		)
		(pin "K9"
		)
		(pin "M5"
		)
		(pin "M6"
		)
		(pin "N7"
		)
		(pin "P13"
		)
		(pin "T1"
		)
		(pin "T16"
		)
		(instances
			(project "sdi-mipi-video-converter"
				(path ""
					(reference "U11")
					(unit 2)
				)
			)
		)
	)
	(symbol
		(lib_id "antmicroLEDIndicationDiscrete:LED_G_0603_LTST-C190GKT")
		(at 383.54 229.87 270)
		(mirror x)
		(unit 1)
		(exclude_from_sim no)
		(in_bom yes)
		(on_board yes)
		(dnp no)
		(property "Reference" "D13"
			(at 387.35 227.3301 90)
			(effects
				(font
					(size 1.27 1.27)
					(thickness 0.15)
				)
				(justify left)
			)
		)
		(property "Value" "LED_G_0603_LTST-C190GKT"
			(at 380.746 233.68 0)
			(effects
				(font
					(size 1.27 1.27)
					(thickness 0.15)
				)
				(justify left)
			)
		)
		(property "Footprint" "antmicro-footprints:LED_0603_1608Metric_G"
			(at 373.38 207.01 0)
			(effects
				(font
					(size 1.27 1.27)
					(thickness 0.15)
				)
				(justify left bottom)
				(hide yes)
			)
		)
		(property "Datasheet" "https://media.digikey.com/pdf/Data%20Sheets/Lite-On%20PDFs/LTST-C190GKT.pdf"
			(at 370.84 207.01 0)
			(effects
				(font
					(size 1.27 1.27)
					(thickness 0.15)
				)
				(justify left bottom)
				(hide yes)
			)
		)
		(property "Description" "LED, Green, SMD, 0603, 20 mA, 2.1 V, 569 nm"
			(at 383.54 229.87 0)
			(effects
				(font
					(size 1.27 1.27)
				)
				(hide yes)
			)
		)
		(property "MPN" "LTST-C190GKT"
			(at 368.3 207.01 0)
			(effects
				(font
					(size 1.27 1.27)
					(thickness 0.15)
				)
				(justify left bottom)
				(hide yes)
			)
		)
		(property "Manufacturer" "Lite-On"
			(at 365.76 207.01 0)
			(effects
				(font
					(size 1.27 1.27)
					(thickness 0.15)
				)
				(justify left bottom)
				(hide yes)
			)
		)
		(property "Author" "Antmicro"
			(at 363.22 207.01 0)
			(effects
				(font
					(size 1.27 1.27)
					(thickness 0.15)
				)
				(justify left bottom)
				(hide yes)
			)
		)
		(property "License" "Apache-2.0"
			(at 360.68 207.01 0)
			(effects
				(font
					(size 1.27 1.27)
					(thickness 0.15)
				)
				(justify left bottom)
				(hide yes)
			)
		)
		(property "Color" "Green"
			(at 378.46 207.01 0)
			(effects
				(font
					(size 1.27 1.27)
				)
				(justify left bottom)
				(hide yes)
			)
		)
		(pin "1"
		)
		(pin "2"
		)
		(instances
			(project "sdi-mipi-video-converter"
				(path ""
					(reference "D13")
					(unit 1)
				)
			)
		)
	)
	(symbol
		(lib_id "antmicroTestPoints:TP_0.75mm_SMD")
		(at 341.63 229.87 0)
		(unit 1)
		(exclude_from_sim no)
		(in_bom yes)
		(on_board yes)
		(dnp no)
		(fields_autoplaced yes)
		(property "Reference" "TP46"
			(at 346.71 229.8699 0)
			(effects
				(font
					(size 1.27 1.27)
					(thickness 0.15)
				)
				(justify left)
			)
		)
		(property "Value" "TP_0.75mm_SMD"
			(at 359.41 237.49 0)
			(effects
				(font
					(size 1.27 1.27)
					(thickness 0.15)
				)
				(justify left bottom)
				(hide yes)
			)
		)
		(property "Footprint" "antmicro-footprints:TP_SMD_0.75mm"
			(at 359.41 240.03 0)
			(effects
				(font
					(size 1.27 1.27)
					(thickness 0.15)
				)
				(justify left bottom)
				(hide yes)
			)
		)
		(property "Datasheet" ""
			(at 359.41 242.57 0)
			(effects
				(font
					(size 1.27 1.27)
					(thickness 0.15)
				)
				(justify left bottom)
				(hide yes)
			)
		)
		(property "Description" "SMT test point"
			(at 341.63 229.87 0)
			(effects
				(font
					(size 1.27 1.27)
				)
				(hide yes)
			)
		)
		(property "MPN" ""
			(at 359.41 245.11 0)
			(effects
				(font
					(size 1.27 1.27)
					(thickness 0.15)
				)
				(justify left bottom)
				(hide yes)
			)
		)
		(property "Manufacturer" ""
			(at 359.41 247.65 0)
			(effects
				(font
					(size 1.27 1.27)
					(thickness 0.15)
				)
				(justify left bottom)
				(hide yes)
			)
		)
		(property "Author" "Antmicro"
			(at 359.41 250.19 0)
			(effects
				(font
					(size 1.27 1.27)
					(thickness 0.15)
				)
				(justify left bottom)
				(hide yes)
			)
		)
		(property "License" "Apache-2.0"
			(at 359.41 252.73 0)
			(effects
				(font
					(size 1.27 1.27)
					(thickness 0.15)
				)
				(justify left bottom)
				(hide yes)
			)
		)
		(pin "1"
		)
		(instances
			(project "sdi-mipi-video-converter"
				(path ""
					(reference "TP46")
					(unit 1)
				)
			)
		)
	)
	(symbol
		(lib_id "antmicroResistors0402:R_27R_0402")
		(at 287.02 228.6 0)
		(unit 1)
		(exclude_from_sim no)
		(in_bom yes)
		(on_board yes)
		(dnp no)
		(property "Reference" "R133"
			(at 284.48 227.33 0)
			(effects
				(font
					(size 1.27 1.27)
					(thickness 0.15)
				)
			)
		)
		(property "Value" "R_27R_0402"
			(at 307.34 241.3 0)
			(effects
				(font
					(size 1.27 1.27)
					(thickness 0.15)
				)
				(justify left bottom)
				(hide yes)
			)
		)
		(property "Footprint" "antmicro-footprints:R_0402_1005Metric"
			(at 307.34 243.84 0)
			(effects
				(font
					(size 1.27 1.27)
					(thickness 0.15)
				)
				(justify left bottom)
				(hide yes)
			)
		)
		(property "Datasheet" "https://www.bourns.com/docs/product-datasheets/cr.pdf"
			(at 307.34 246.38 0)
			(effects
				(font
					(size 1.27 1.27)
					(thickness 0.15)
				)
				(justify left bottom)
				(hide yes)
			)
		)
		(property "Description" "SMD Chip Resistor, 27 ohm, ± 1%, 63 mW, 0402 [1005 Metric], Thick Film, General Purpose"
			(at 287.02 228.6 0)
			(effects
				(font
					(size 1.27 1.27)
				)
				(hide yes)
			)
		)
		(property "Manufacturer" "Bourns"
			(at 307.34 251.46 0)
			(effects
				(font
					(size 1.27 1.27)
					(thickness 0.15)
				)
				(justify left bottom)
				(hide yes)
			)
		)
		(property "MPN" "CR0402-FX-27R0GLF"
			(at 307.34 248.92 0)
			(effects
				(font
					(size 1.27 1.27)
					(thickness 0.15)
				)
				(justify left bottom)
				(hide yes)
			)
		)
		(property "Val" "27R"
			(at 294.005 227.33 0)
			(effects
				(font
					(size 1.27 1.27)
					(thickness 0.15)
				)
			)
		)
		(property "License" "Apache-2.0"
			(at 307.34 254 0)
			(effects
				(font
					(size 1.27 1.27)
					(thickness 0.15)
				)
				(justify left bottom)
				(hide yes)
			)
		)
		(property "Author" "Antmicro"
			(at 307.34 256.54 0)
			(effects
				(font
					(size 1.27 1.27)
					(thickness 0.15)
				)
				(justify left bottom)
				(hide yes)
			)
		)
		(property "Tolerance" "1%"
			(at 307.34 238.76 0)
			(effects
				(font
					(size 1.27 1.27)
				)
				(justify left bottom)
				(hide yes)
			)
		)
		(pin "1"
		)
		(pin "2"
		)
		(instances
			(project "sdi-mipi-video-converter"
				(path ""
					(reference "R133")
					(unit 1)
				)
			)
		)
	)
	(symbol
		(lib_id "antmicroResistors0603:R_10k_0603")
		(at 72.39 242.57 270)
		(unit 1)
		(exclude_from_sim no)
		(in_bom no)
		(on_board yes)
		(dnp yes)
		(property "Reference" "R115"
			(at 73.66 243.84 90)
			(effects
				(font
					(size 1.27 1.27)
					(thickness 0.15)
				)
				(justify left)
			)
		)
		(property "Value" "R_10k_0603"
			(at 59.69 262.89 0)
			(effects
				(font
					(size 1.27 1.27)
					(thickness 0.15)
				)
				(justify left bottom)
				(hide yes)
			)
		)
		(property "Footprint" "antmicro-footprints:R_0603_1608Metric"
			(at 57.15 262.89 0)
			(effects
				(font
					(size 1.27 1.27)
					(thickness 0.15)
				)
				(justify left bottom)
				(hide yes)
			)
		)
		(property "Datasheet" "https://www.bourns.com/docs/product-datasheets/cr.pdf"
			(at 54.61 262.89 0)
			(effects
				(font
					(size 1.27 1.27)
					(thickness 0.15)
				)
				(justify left bottom)
				(hide yes)
			)
		)
		(property "Description" "SMD Chip Resistor, 10 kohm, ± 1%, 100 mW, 0603 [1608 Metric], Thick Film, General Purpose"
			(at 72.39 242.57 0)
			(effects
				(font
					(size 1.27 1.27)
				)
				(hide yes)
			)
		)
		(property "Manufacturer" "Bourns"
			(at 49.53 262.89 0)
			(effects
				(font
					(size 1.27 1.27)
					(thickness 0.15)
				)
				(justify left bottom)
				(hide yes)
			)
		)
		(property "MPN" "CR0603-FX-1002ELF"
			(at 52.07 262.89 0)
			(effects
				(font
					(size 1.27 1.27)
					(thickness 0.15)
				)
				(justify left bottom)
				(hide yes)
			)
		)
		(property "Val" "10k"
			(at 73.66 246.38 90)
			(effects
				(font
					(size 1.27 1.27)
					(thickness 0.15)
				)
				(justify left)
			)
		)
		(property "License" "Apache-2.0"
			(at 46.99 262.89 0)
			(effects
				(font
					(size 1.27 1.27)
					(thickness 0.15)
				)
				(justify left bottom)
				(hide yes)
			)
		)
		(property "Author" "Antmicro"
			(at 44.45 262.89 0)
			(effects
				(font
					(size 1.27 1.27)
					(thickness 0.15)
				)
				(justify left bottom)
				(hide yes)
			)
		)
		(property "Tolerance" "1%"
			(at 62.23 262.89 0)
			(effects
				(font
					(size 1.27 1.27)
				)
				(justify left bottom)
				(hide yes)
			)
		)
		(pin "1"
		)
		(pin "2"
		)
		(instances
			(project "sdi-mipi-video-converter"
				(path ""
					(reference "R115")
					(unit 1)
				)
			)
		)
	)
	(symbol
		(lib_id "antmicroResistors0603:R_10k_0603")
		(at 165.1 229.87 270)
		(unit 1)
		(exclude_from_sim no)
		(in_bom yes)
		(on_board yes)
		(dnp no)
		(property "Reference" "R105"
			(at 163.83 231.14 90)
			(effects
				(font
					(size 1.27 1.27)
					(thickness 0.15)
				)
				(justify right)
			)
		)
		(property "Value" "R_10k_0603"
			(at 152.4 250.19 0)
			(effects
				(font
					(size 1.27 1.27)
					(thickness 0.15)
				)
				(justify left bottom)
				(hide yes)
			)
		)
		(property "Footprint" "antmicro-footprints:R_0603_1608Metric"
			(at 149.86 250.19 0)
			(effects
				(font
					(size 1.27 1.27)
					(thickness 0.15)
				)
				(justify left bottom)
				(hide yes)
			)
		)
		(property "Datasheet" "https://www.bourns.com/docs/product-datasheets/cr.pdf"
			(at 147.32 250.19 0)
			(effects
				(font
					(size 1.27 1.27)
					(thickness 0.15)
				)
				(justify left bottom)
				(hide yes)
			)
		)
		(property "Description" "SMD Chip Resistor, 10 kohm, ± 1%, 100 mW, 0603 [1608 Metric], Thick Film, General Purpose"
			(at 165.1 229.87 0)
			(effects
				(font
					(size 1.27 1.27)
				)
				(hide yes)
			)
		)
		(property "Manufacturer" "Bourns"
			(at 142.24 250.19 0)
			(effects
				(font
					(size 1.27 1.27)
					(thickness 0.15)
				)
				(justify left bottom)
				(hide yes)
			)
		)
		(property "MPN" "CR0603-FX-1002ELF"
			(at 144.78 250.19 0)
			(effects
				(font
					(size 1.27 1.27)
					(thickness 0.15)
				)
				(justify left bottom)
				(hide yes)
			)
		)
		(property "Val" "10k"
			(at 163.83 233.68 90)
			(effects
				(font
					(size 1.27 1.27)
					(thickness 0.15)
				)
				(justify right)
			)
		)
		(property "License" "Apache-2.0"
			(at 139.7 250.19 0)
			(effects
				(font
					(size 1.27 1.27)
					(thickness 0.15)
				)
				(justify left bottom)
				(hide yes)
			)
		)
		(property "Author" "Antmicro"
			(at 137.16 250.19 0)
			(effects
				(font
					(size 1.27 1.27)
					(thickness 0.15)
				)
				(justify left bottom)
				(hide yes)
			)
		)
		(property "Tolerance" "1%"
			(at 154.94 250.19 0)
			(effects
				(font
					(size 1.27 1.27)
				)
				(justify left bottom)
				(hide yes)
			)
		)
		(pin "1"
		)
		(pin "2"
		)
		(instances
			(project "sdi-mipi-video-converter"
				(path ""
					(reference "R105")
					(unit 1)
				)
			)
		)
	)
	(symbol
		(lib_id "antmicroResistors0603:R_200R_0603")
		(at 318.77 143.51 90)
		(unit 1)
		(exclude_from_sim no)
		(in_bom yes)
		(on_board yes)
		(dnp no)
		(fields_autoplaced yes)
		(property "Reference" "R112"
			(at 321.31 139.6999 90)
			(effects
				(font
					(size 1.27 1.27)
					(thickness 0.15)
				)
				(justify right)
			)
		)
		(property "Value" "R_200R_0603"
			(at 331.47 123.19 0)
			(effects
				(font
					(size 1.27 1.27)
					(thickness 0.15)
				)
				(justify left bottom)
				(hide yes)
			)
		)
		(property "Footprint" "antmicro-footprints:R_0603_1608Metric"
			(at 334.01 123.19 0)
			(effects
				(font
					(size 1.27 1.27)
					(thickness 0.15)
				)
				(justify left bottom)
				(hide yes)
			)
		)
		(property "Datasheet" "https://www.bourns.com/docs/product-datasheets/cr.pdf"
			(at 336.55 123.19 0)
			(effects
				(font
					(size 1.27 1.27)
					(thickness 0.15)
				)
				(justify left bottom)
				(hide yes)
			)
		)
		(property "Description" "SMD Chip Resistor, 200 ohm, ± 1%, 100 mW, 0603 [1608 Metric], Thick Film, General Purpose"
			(at 318.77 143.51 0)
			(effects
				(font
					(size 1.27 1.27)
				)
				(hide yes)
			)
		)
		(property "Manufacturer" "Bourns"
			(at 341.63 123.19 0)
			(effects
				(font
					(size 1.27 1.27)
					(thickness 0.15)
				)
				(justify left bottom)
				(hide yes)
			)
		)
		(property "MPN" "CR0603-FX-2000ELF"
			(at 339.09 123.19 0)
			(effects
				(font
					(size 1.27 1.27)
					(thickness 0.15)
				)
				(justify left bottom)
				(hide yes)
			)
		)
		(property "Val" "200R"
			(at 321.31 142.2399 90)
			(effects
				(font
					(size 1.27 1.27)
					(thickness 0.15)
				)
				(justify right)
			)
		)
		(property "License" "Apache-2.0"
			(at 344.17 123.19 0)
			(effects
				(font
					(size 1.27 1.27)
					(thickness 0.15)
				)
				(justify left bottom)
				(hide yes)
			)
		)
		(property "Author" "Antmicro"
			(at 346.71 123.19 0)
			(effects
				(font
					(size 1.27 1.27)
					(thickness 0.15)
				)
				(justify left bottom)
				(hide yes)
			)
		)
		(property "Tolerance" "1%"
			(at 328.93 123.19 0)
			(effects
				(font
					(size 1.27 1.27)
				)
				(justify left bottom)
				(hide yes)
			)
		)
		(pin "1"
		)
		(pin "2"
		)
		(instances
			(project "sdi-mipi-video-converter"
				(path ""
					(reference "R112")
					(unit 1)
				)
			)
		)
	)
	(symbol
		(lib_id "antmicroResistors0603:R_15k_0603")
		(at 199.39 233.68 90)
		(unit 1)
		(exclude_from_sim no)
		(in_bom yes)
		(on_board yes)
		(dnp no)
		(property "Reference" "R107"
			(at 200.66 229.87 90)
			(effects
				(font
					(size 1.27 1.27)
					(thickness 0.15)
				)
				(justify right)
			)
		)
		(property "Value" "R_15k_0603"
			(at 212.09 213.36 0)
			(effects
				(font
					(size 1.27 1.27)
					(thickness 0.15)
				)
				(justify left bottom)
				(hide yes)
			)
		)
		(property "Footprint" "antmicro-footprints:R_0603_1608Metric"
			(at 214.63 213.36 0)
			(effects
				(font
					(size 1.27 1.27)
					(thickness 0.15)
				)
				(justify left bottom)
				(hide yes)
			)
		)
		(property "Datasheet" "https://www.bourns.com/docs/product-datasheets/cr.pdf"
			(at 217.17 213.36 0)
			(effects
				(font
					(size 1.27 1.27)
					(thickness 0.15)
				)
				(justify left bottom)
				(hide yes)
			)
		)
		(property "Description" "SMD Chip Resistor, 15 kohm, ± 1%, 100 mW, 0603 [1608 Metric], Thick Film, General Purpose"
			(at 199.39 233.68 0)
			(effects
				(font
					(size 1.27 1.27)
				)
				(hide yes)
			)
		)
		(property "Manufacturer" "Bourns"
			(at 222.25 213.36 0)
			(effects
				(font
					(size 1.27 1.27)
					(thickness 0.15)
				)
				(justify left bottom)
				(hide yes)
			)
		)
		(property "MPN" "CR0603-FX-1502ELF"
			(at 219.71 213.36 0)
			(effects
				(font
					(size 1.27 1.27)
					(thickness 0.15)
				)
				(justify left bottom)
				(hide yes)
			)
		)
		(property "Val" "15k"
			(at 200.66 232.41 90)
			(effects
				(font
					(size 1.27 1.27)
					(thickness 0.15)
				)
				(justify right)
			)
		)
		(property "License" "Apache-2.0"
			(at 224.79 213.36 0)
			(effects
				(font
					(size 1.27 1.27)
					(thickness 0.15)
				)
				(justify left bottom)
				(hide yes)
			)
		)
		(property "Author" "Antmicro"
			(at 227.33 213.36 0)
			(effects
				(font
					(size 1.27 1.27)
					(thickness 0.15)
				)
				(justify left bottom)
				(hide yes)
			)
		)
		(property "Tolerance" "1%"
			(at 209.55 213.36 0)
			(effects
				(font
					(size 1.27 1.27)
				)
				(justify left bottom)
				(hide yes)
			)
		)
		(pin "1"
		)
		(pin "2"
		)
		(instances
			(project "sdi-mipi-video-converter"
				(path ""
					(reference "R107")
					(unit 1)
				)
			)
		)
	)
	(symbol
		(lib_id "antmicroResistors0402:R_0R_0402")
		(at 224.79 143.51 0)
		(unit 1)
		(exclude_from_sim no)
		(in_bom yes)
		(on_board yes)
		(dnp no)
		(property "Reference" "R126"
			(at 222.25 144.78 0)
			(effects
				(font
					(size 1.27 1.27)
					(thickness 0.15)
				)
			)
		)
		(property "Value" "R_0R_0402"
			(at 245.11 156.21 0)
			(effects
				(font
					(size 1.27 1.27)
					(thickness 0.15)
				)
				(justify left bottom)
				(hide yes)
			)
		)
		(property "Footprint" "antmicro-footprints:R_0402_1005Metric"
			(at 245.11 158.75 0)
			(effects
				(font
					(size 1.27 1.27)
					(thickness 0.15)
				)
				(justify left bottom)
				(hide yes)
			)
		)
		(property "Datasheet" "https://industrial.panasonic.com/cdbs/www-data/pdf/RDA0000/AOA0000C301.pdf"
			(at 245.11 161.29 0)
			(effects
				(font
					(size 1.27 1.27)
					(thickness 0.15)
				)
				(justify left bottom)
				(hide yes)
			)
		)
		(property "Description" "SMD Chip Resistor, Jumper, 0 ohm, 100 mW, 0402 [1005 Metric], Thick Film, General Purpose"
			(at 224.79 143.51 0)
			(effects
				(font
					(size 1.27 1.27)
				)
				(hide yes)
			)
		)
		(property "Manufacturer" "Panasonic"
			(at 245.11 166.37 0)
			(effects
				(font
					(size 1.27 1.27)
					(thickness 0.15)
				)
				(justify left bottom)
				(hide yes)
			)
		)
		(property "MPN" "ERJ2GE0R00X"
			(at 245.11 163.83 0)
			(effects
				(font
					(size 1.27 1.27)
					(thickness 0.15)
				)
				(justify left bottom)
				(hide yes)
			)
		)
		(property "Val" "0R"
			(at 231.14 144.78 0)
			(effects
				(font
					(size 1.27 1.27)
					(thickness 0.15)
				)
			)
		)
		(property "License" "Apache-2.0"
			(at 245.11 168.91 0)
			(effects
				(font
					(size 1.27 1.27)
					(thickness 0.15)
				)
				(justify left bottom)
				(hide yes)
			)
		)
		(property "Author" "Antmicro"
			(at 245.11 171.45 0)
			(effects
				(font
					(size 1.27 1.27)
					(thickness 0.15)
				)
				(justify left bottom)
				(hide yes)
			)
		)
		(property "Tolerance" "~"
			(at 245.11 153.67 0)
			(effects
				(font
					(size 1.27 1.27)
				)
				(justify left bottom)
				(hide yes)
			)
		)
		(property "Current" "1A"
			(at 245.11 173.99 0)
			(effects
				(font
					(size 1.27 1.27)
					(thickness 0.15)
				)
				(justify left bottom)
				(hide yes)
			)
		)
		(pin "1"
		)
		(pin "2"
		)
		(instances
			(project "sdi-mipi-video-converter"
				(path ""
					(reference "R126")
					(unit 1)
				)
			)
		)
	)
	(symbol
		(lib_id "antmicropower:GND")
		(at 158.75 176.53 0)
		(unit 1)
		(exclude_from_sim no)
		(in_bom yes)
		(on_board yes)
		(dnp no)
		(fields_autoplaced yes)
		(property "Reference" "#PWR0250"
			(at 167.64 179.07 0)
			(effects
				(font
					(size 1.27 1.27)
					(thickness 0.15)
				)
				(justify left bottom)
				(hide yes)
			)
		)
		(property "Value" "GND"
			(at 158.75 181.61 0)
			(effects
				(font
					(size 1.27 1.27)
					(thickness 0.15)
				)
			)
		)
		(property "Footprint" ""
			(at 167.64 184.15 0)
			(effects
				(font
					(size 1.27 1.27)
					(thickness 0.15)
				)
				(justify left bottom)
				(hide yes)
			)
		)
		(property "Datasheet" ""
			(at 167.64 189.23 0)
			(effects
				(font
					(size 1.27 1.27)
					(thickness 0.15)
				)
				(justify left bottom)
				(hide yes)
			)
		)
		(property "Description" ""
			(at 158.75 176.53 0)
			(effects
				(font
					(size 1.27 1.27)
				)
				(hide yes)
			)
		)
		(property "Author" "Antmicro"
			(at 167.64 184.15 0)
			(effects
				(font
					(size 1.27 1.27)
					(thickness 0.15)
				)
				(justify left bottom)
				(hide yes)
			)
		)
		(property "License" "Apache-2.0"
			(at 167.64 186.69 0)
			(effects
				(font
					(size 1.27 1.27)
					(thickness 0.15)
				)
				(justify left bottom)
				(hide yes)
			)
		)
		(pin "1"
		)
		(instances
			(project "sdi-mipi-video-converter"
				(path ""
					(reference "#PWR0250")
					(unit 1)
				)
			)
		)
	)
	(symbol
		(lib_id "antmicropower:+3.3V")
		(at 53.34 227.33 0)
		(unit 1)
		(exclude_from_sim no)
		(in_bom yes)
		(on_board yes)
		(dnp no)
		(fields_autoplaced yes)
		(property "Reference" "#PWR05"
			(at 53.34 231.14 0)
			(effects
				(font
					(size 1.27 1.27)
				)
				(hide yes)
			)
		)
		(property "Value" "+3V3"
			(at 53.34 222.25 0)
			(effects
				(font
					(size 1.27 1.27)
				)
			)
		)
		(property "Footprint" ""
			(at 53.34 227.33 0)
			(effects
				(font
					(size 1.27 1.27)
				)
				(hide yes)
			)
		)
		(property "Datasheet" ""
			(at 53.34 227.33 0)
			(effects
				(font
					(size 1.27 1.27)
				)
				(hide yes)
			)
		)
		(property "Description" ""
			(at 53.34 227.33 0)
			(effects
				(font
					(size 1.27 1.27)
				)
				(hide yes)
			)
		)
		(pin "1"
		)
		(instances
			(project "sdi-mipi-video-converter"
				(path ""
					(reference "#PWR05")
					(unit 1)
				)
			)
		)
	)
	(symbol
		(lib_id "antmicropower:+5V")
		(at 148.59 247.65 0)
		(unit 1)
		(exclude_from_sim no)
		(in_bom yes)
		(on_board yes)
		(dnp no)
		(fields_autoplaced yes)
		(property "Reference" "#PWR0152"
			(at 163.83 250.19 0)
			(effects
				(font
					(size 1.27 1.27)
					(thickness 0.15)
				)
				(justify left bottom)
				(hide yes)
			)
		)
		(property "Value" "+5V"
			(at 148.59 242.57 0)
			(effects
				(font
					(size 1.27 1.27)
					(thickness 0.15)
				)
			)
		)
		(property "Footprint" ""
			(at 163.83 255.27 0)
			(effects
				(font
					(size 1.27 1.27)
					(thickness 0.15)
				)
				(justify left bottom)
				(hide yes)
			)
		)
		(property "Datasheet" ""
			(at 163.83 257.81 0)
			(effects
				(font
					(size 1.27 1.27)
					(thickness 0.15)
				)
				(justify left bottom)
				(hide yes)
			)
		)
		(property "Description" ""
			(at 148.59 247.65 0)
			(effects
				(font
					(size 1.27 1.27)
				)
				(hide yes)
			)
		)
		(property "Author" "Antmicro"
			(at 163.83 255.27 0)
			(effects
				(font
					(size 1.27 1.27)
					(thickness 0.15)
				)
				(justify left bottom)
				(hide yes)
			)
		)
		(property "License" "Apache-2.0"
			(at 163.83 257.81 0)
			(effects
				(font
					(size 1.27 1.27)
					(thickness 0.15)
				)
				(justify left bottom)
				(hide yes)
			)
		)
		(pin "1"
		)
		(instances
			(project "sdi-mipi-video-converter"
				(path ""
					(reference "#PWR0152")
					(unit 1)
				)
			)
		)
	)
	(symbol
		(lib_id "antmicroResistors0603:R_15k_0603")
		(at 110.49 242.57 90)
		(unit 1)
		(exclude_from_sim no)
		(in_bom yes)
		(on_board yes)
		(dnp no)
		(fields_autoplaced yes)
		(property "Reference" "R118"
			(at 113.03 238.7599 90)
			(effects
				(font
					(size 1.27 1.27)
					(thickness 0.15)
				)
				(justify right)
			)
		)
		(property "Value" "R_15k_0603"
			(at 123.19 222.25 0)
			(effects
				(font
					(size 1.27 1.27)
					(thickness 0.15)
				)
				(justify left bottom)
				(hide yes)
			)
		)
		(property "Footprint" "antmicro-footprints:R_0603_1608Metric"
			(at 125.73 222.25 0)
			(effects
				(font
					(size 1.27 1.27)
					(thickness 0.15)
				)
				(justify left bottom)
				(hide yes)
			)
		)
		(property "Datasheet" "https://www.bourns.com/docs/product-datasheets/cr.pdf"
			(at 128.27 222.25 0)
			(effects
				(font
					(size 1.27 1.27)
					(thickness 0.15)
				)
				(justify left bottom)
				(hide yes)
			)
		)
		(property "Description" "SMD Chip Resistor, 15 kohm, ± 1%, 100 mW, 0603 [1608 Metric], Thick Film, General Purpose"
			(at 110.49 242.57 0)
			(effects
				(font
					(size 1.27 1.27)
				)
				(hide yes)
			)
		)
		(property "Manufacturer" "Bourns"
			(at 133.35 222.25 0)
			(effects
				(font
					(size 1.27 1.27)
					(thickness 0.15)
				)
				(justify left bottom)
				(hide yes)
			)
		)
		(property "MPN" "CR0603-FX-1502ELF"
			(at 130.81 222.25 0)
			(effects
				(font
					(size 1.27 1.27)
					(thickness 0.15)
				)
				(justify left bottom)
				(hide yes)
			)
		)
		(property "Val" "15k"
			(at 113.03 241.2999 90)
			(effects
				(font
					(size 1.27 1.27)
					(thickness 0.15)
				)
				(justify right)
			)
		)
		(property "License" "Apache-2.0"
			(at 135.89 222.25 0)
			(effects
				(font
					(size 1.27 1.27)
					(thickness 0.15)
				)
				(justify left bottom)
				(hide yes)
			)
		)
		(property "Author" "Antmicro"
			(at 138.43 222.25 0)
			(effects
				(font
					(size 1.27 1.27)
					(thickness 0.15)
				)
				(justify left bottom)
				(hide yes)
			)
		)
		(property "Tolerance" "1%"
			(at 120.65 222.25 0)
			(effects
				(font
					(size 1.27 1.27)
				)
				(justify left bottom)
				(hide yes)
			)
		)
		(pin "1"
		)
		(pin "2"
		)
		(instances
			(project "sdi-mipi-video-converter"
				(path ""
					(reference "R118")
					(unit 1)
				)
			)
		)
	)
	(symbol
		(lib_id "antmicropower:GND")
		(at 285.75 210.82 0)
		(unit 1)
		(exclude_from_sim no)
		(in_bom yes)
		(on_board yes)
		(dnp no)
		(fields_autoplaced yes)
		(property "Reference" "#PWR0272"
			(at 294.64 213.36 0)
			(effects
				(font
					(size 1.27 1.27)
					(thickness 0.15)
				)
				(justify left bottom)
				(hide yes)
			)
		)
		(property "Value" "GND"
			(at 285.75 215.9 0)
			(effects
				(font
					(size 1.27 1.27)
					(thickness 0.15)
				)
			)
		)
		(property "Footprint" ""
			(at 294.64 218.44 0)
			(effects
				(font
					(size 1.27 1.27)
					(thickness 0.15)
				)
				(justify left bottom)
				(hide yes)
			)
		)
		(property "Datasheet" ""
			(at 294.64 223.52 0)
			(effects
				(font
					(size 1.27 1.27)
					(thickness 0.15)
				)
				(justify left bottom)
				(hide yes)
			)
		)
		(property "Description" ""
			(at 285.75 210.82 0)
			(effects
				(font
					(size 1.27 1.27)
				)
				(hide yes)
			)
		)
		(property "Author" "Antmicro"
			(at 294.64 218.44 0)
			(effects
				(font
					(size 1.27 1.27)
					(thickness 0.15)
				)
				(justify left bottom)
				(hide yes)
			)
		)
		(property "License" "Apache-2.0"
			(at 294.64 220.98 0)
			(effects
				(font
					(size 1.27 1.27)
					(thickness 0.15)
				)
				(justify left bottom)
				(hide yes)
			)
		)
		(pin "1"
		)
		(instances
			(project "sdi-mipi-video-converter"
				(path ""
					(reference "#PWR0272")
					(unit 1)
				)
			)
		)
	)
	(symbol
		(lib_id "antmicroResistors0603:R_200R_0603")
		(at 87.63 205.74 90)
		(unit 1)
		(exclude_from_sim no)
		(in_bom yes)
		(on_board yes)
		(dnp no)
		(fields_autoplaced yes)
		(property "Reference" "R120"
			(at 90.17 201.9299 90)
			(effects
				(font
					(size 1.27 1.27)
					(thickness 0.15)
				)
				(justify right)
			)
		)
		(property "Value" "R_200R_0603"
			(at 100.33 185.42 0)
			(effects
				(font
					(size 1.27 1.27)
					(thickness 0.15)
				)
				(justify left bottom)
				(hide yes)
			)
		)
		(property "Footprint" "antmicro-footprints:R_0603_1608Metric"
			(at 102.87 185.42 0)
			(effects
				(font
					(size 1.27 1.27)
					(thickness 0.15)
				)
				(justify left bottom)
				(hide yes)
			)
		)
		(property "Datasheet" "https://www.bourns.com/docs/product-datasheets/cr.pdf"
			(at 105.41 185.42 0)
			(effects
				(font
					(size 1.27 1.27)
					(thickness 0.15)
				)
				(justify left bottom)
				(hide yes)
			)
		)
		(property "Description" "SMD Chip Resistor, 200 ohm, ± 1%, 100 mW, 0603 [1608 Metric], Thick Film, General Purpose"
			(at 87.63 205.74 0)
			(effects
				(font
					(size 1.27 1.27)
				)
				(hide yes)
			)
		)
		(property "Manufacturer" "Bourns"
			(at 110.49 185.42 0)
			(effects
				(font
					(size 1.27 1.27)
					(thickness 0.15)
				)
				(justify left bottom)
				(hide yes)
			)
		)
		(property "MPN" "CR0603-FX-2000ELF"
			(at 107.95 185.42 0)
			(effects
				(font
					(size 1.27 1.27)
					(thickness 0.15)
				)
				(justify left bottom)
				(hide yes)
			)
		)
		(property "Val" "200R"
			(at 90.17 204.4699 90)
			(effects
				(font
					(size 1.27 1.27)
					(thickness 0.15)
				)
				(justify right)
			)
		)
		(property "License" "Apache-2.0"
			(at 113.03 185.42 0)
			(effects
				(font
					(size 1.27 1.27)
					(thickness 0.15)
				)
				(justify left bottom)
				(hide yes)
			)
		)
		(property "Author" "Antmicro"
			(at 115.57 185.42 0)
			(effects
				(font
					(size 1.27 1.27)
					(thickness 0.15)
				)
				(justify left bottom)
				(hide yes)
			)
		)
		(property "Tolerance" "1%"
			(at 97.79 185.42 0)
			(effects
				(font
					(size 1.27 1.27)
				)
				(justify left bottom)
				(hide yes)
			)
		)
		(pin "1"
		)
		(pin "2"
		)
		(instances
			(project "sdi-mipi-video-converter"
				(path ""
					(reference "R120")
					(unit 1)
				)
			)
		)
	)
	(symbol
		(lib_id "antmicroLEDIndicationDiscrete:LED_G_0603_LTST-C190GKT")
		(at 306.07 154.94 270)
		(mirror x)
		(unit 1)
		(exclude_from_sim no)
		(in_bom yes)
		(on_board yes)
		(dnp no)
		(property "Reference" "D3"
			(at 301.244 151.13 90)
			(effects
				(font
					(size 1.27 1.27)
					(thickness 0.15)
				)
				(justify left)
			)
		)
		(property "Value" "LED_G_0603_LTST-C190GKT"
			(at 277.876 154.432 90)
			(effects
				(font
					(size 1.27 1.27)
					(thickness 0.15)
				)
				(justify left)
			)
		)
		(property "Footprint" "antmicro-footprints:LED_0603_1608Metric_G"
			(at 295.91 132.08 0)
			(effects
				(font
					(size 1.27 1.27)
					(thickness 0.15)
				)
				(justify left bottom)
				(hide yes)
			)
		)
		(property "Datasheet" "https://media.digikey.com/pdf/Data%20Sheets/Lite-On%20PDFs/LTST-C190GKT.pdf"
			(at 293.37 132.08 0)
			(effects
				(font
					(size 1.27 1.27)
					(thickness 0.15)
				)
				(justify left bottom)
				(hide yes)
			)
		)
		(property "Description" "LED, Green, SMD, 0603, 20 mA, 2.1 V, 569 nm"
			(at 306.07 154.94 0)
			(effects
				(font
					(size 1.27 1.27)
				)
				(hide yes)
			)
		)
		(property "MPN" "LTST-C190GKT"
			(at 290.83 132.08 0)
			(effects
				(font
					(size 1.27 1.27)
					(thickness 0.15)
				)
				(justify left bottom)
				(hide yes)
			)
		)
		(property "Manufacturer" "Lite-On"
			(at 288.29 132.08 0)
			(effects
				(font
					(size 1.27 1.27)
					(thickness 0.15)
				)
				(justify left bottom)
				(hide yes)
			)
		)
		(property "Author" "Antmicro"
			(at 285.75 132.08 0)
			(effects
				(font
					(size 1.27 1.27)
					(thickness 0.15)
				)
				(justify left bottom)
				(hide yes)
			)
		)
		(property "License" "Apache-2.0"
			(at 283.21 132.08 0)
			(effects
				(font
					(size 1.27 1.27)
					(thickness 0.15)
				)
				(justify left bottom)
				(hide yes)
			)
		)
		(property "Color" "Green"
			(at 300.99 132.08 0)
			(effects
				(font
					(size 1.27 1.27)
				)
				(justify left bottom)
				(hide yes)
			)
		)
		(pin "1"
		)
		(pin "2"
		)
		(instances
			(project "sdi-mipi-video-converter"
				(path ""
					(reference "D3")
					(unit 1)
				)
			)
		)
	)
	(symbol
		(lib_id "antmicroResistors0402:R_0R_0402")
		(at 176.53 113.03 0)
		(unit 1)
		(exclude_from_sim no)
		(in_bom yes)
		(on_board yes)
		(dnp no)
		(property "Reference" "R73"
			(at 174.625 114.3 0)
			(effects
				(font
					(size 1.27 1.27)
					(thickness 0.15)
				)
			)
		)
		(property "Value" "R_0R_0402"
			(at 196.85 125.73 0)
			(effects
				(font
					(size 1.27 1.27)
					(thickness 0.15)
				)
				(justify left bottom)
				(hide yes)
			)
		)
		(property "Footprint" "antmicro-footprints:R_0402_1005Metric"
			(at 196.85 128.27 0)
			(effects
				(font
					(size 1.27 1.27)
					(thickness 0.15)
				)
				(justify left bottom)
				(hide yes)
			)
		)
		(property "Datasheet" "https://industrial.panasonic.com/cdbs/www-data/pdf/RDA0000/AOA0000C301.pdf"
			(at 196.85 130.81 0)
			(effects
				(font
					(size 1.27 1.27)
					(thickness 0.15)
				)
				(justify left bottom)
				(hide yes)
			)
		)
		(property "Description" "SMD Chip Resistor, Jumper, 0 ohm, 100 mW, 0402 [1005 Metric], Thick Film, General Purpose"
			(at 176.53 113.03 0)
			(effects
				(font
					(size 1.27 1.27)
				)
				(hide yes)
			)
		)
		(property "Manufacturer" "Panasonic"
			(at 196.85 135.89 0)
			(effects
				(font
					(size 1.27 1.27)
					(thickness 0.15)
				)
				(justify left bottom)
				(hide yes)
			)
		)
		(property "MPN" "ERJ2GE0R00X"
			(at 196.85 133.35 0)
			(effects
				(font
					(size 1.27 1.27)
					(thickness 0.15)
				)
				(justify left bottom)
				(hide yes)
			)
		)
		(property "Val" "0R"
			(at 182.88 114.3 0)
			(effects
				(font
					(size 1.27 1.27)
					(thickness 0.15)
				)
			)
		)
		(property "License" "Apache-2.0"
			(at 196.85 138.43 0)
			(effects
				(font
					(size 1.27 1.27)
					(thickness 0.15)
				)
				(justify left bottom)
				(hide yes)
			)
		)
		(property "Author" "Antmicro"
			(at 196.85 140.97 0)
			(effects
				(font
					(size 1.27 1.27)
					(thickness 0.15)
				)
				(justify left bottom)
				(hide yes)
			)
		)
		(property "Tolerance" "~"
			(at 196.85 123.19 0)
			(effects
				(font
					(size 1.27 1.27)
				)
				(justify left bottom)
				(hide yes)
			)
		)
		(property "Current" "1A"
			(at 196.85 143.51 0)
			(effects
				(font
					(size 1.27 1.27)
					(thickness 0.15)
				)
				(justify left bottom)
				(hide yes)
			)
		)
		(pin "1"
		)
		(pin "2"
		)
		(instances
			(project "sdi-mipi-video-converter"
				(path ""
					(reference "R73")
					(unit 1)
				)
			)
		)
	)
	(symbol
		(lib_id "antmicroGenericPinHeaders:PinHeader_2x5_P1.27mm_SMD")
		(at 300.99 52.07 0)
		(unit 1)
		(exclude_from_sim no)
		(in_bom yes)
		(on_board yes)
		(dnp no)
		(fields_autoplaced yes)
		(property "Reference" "J5"
			(at 306.07 45.72 0)
			(effects
				(font
					(size 1.27 1.27)
					(thickness 0.15)
				)
			)
		)
		(property "Value" "PinHeader_2x5_P1.27mm_SMD"
			(at 306.07 48.26 0)
			(effects
				(font
					(size 1.27 1.27)
					(thickness 0.15)
				)
			)
		)
		(property "Footprint" "antmicro-footprints:PinHeader_2x5_P1.27mm_SMD"
			(at 326.39 62.23 0)
			(effects
				(font
					(size 1.27 1.27)
					(thickness 0.15)
				)
				(justify left bottom)
				(hide yes)
			)
		)
		(property "Datasheet" "https://eu.mouser.com/datasheet/2/527/ftsh_th-2854322.pdf"
			(at 326.39 64.77 0)
			(effects
				(font
					(size 1.27 1.27)
					(thickness 0.15)
				)
				(justify left bottom)
				(hide yes)
			)
		)
		(property "Description" "Pin Header, Board-to-Board, Wire-to-Board, 1.27 mm, 2 Rows, 10 Contacts, Surface Mount, FTSH"
			(at 300.99 52.07 0)
			(effects
				(font
					(size 1.27 1.27)
				)
				(hide yes)
			)
		)
		(property "MPN" "FTSH-105-01-F-DV"
			(at 326.39 67.31 0)
			(effects
				(font
					(size 1.27 1.27)
					(thickness 0.15)
				)
				(justify left bottom)
				(hide yes)
			)
		)
		(property "Manufacturer" "Samtec"
			(at 326.39 69.85 0)
			(effects
				(font
					(size 1.27 1.27)
					(thickness 0.15)
				)
				(justify left bottom)
				(hide yes)
			)
		)
		(property "Author" "Antmicro"
			(at 326.39 72.39 0)
			(effects
				(font
					(size 1.27 1.27)
					(thickness 0.15)
				)
				(justify left bottom)
				(hide yes)
			)
		)
		(property "License" "Apache-2.0"
			(at 326.39 74.93 0)
			(effects
				(font
					(size 1.27 1.27)
					(thickness 0.15)
				)
				(justify left bottom)
				(hide yes)
			)
		)
		(pin "1"
		)
		(pin "10"
		)
		(pin "2"
		)
		(pin "3"
		)
		(pin "4"
		)
		(pin "5"
		)
		(pin "6"
		)
		(pin "7"
		)
		(pin "8"
		)
		(pin "9"
		)
		(instances
			(project "sdi-mipi-video-converter"
				(path ""
					(reference "J5")
					(unit 1)
				)
			)
		)
	)
)
